FILE_TYPE = MACRO_DRAWING;
SET COLOR_WIRE YELLOW;
SET COLOR_PROP ORANGE;
SET COLOR_DOT WHITE;
SET COLOR_ARC YELLOW;
SET COLOR_BODY GREEN;
SET COLOR_NOTE PURPLE;
SET PROP_DISPLAY VALUE;
SET PAGE_NUMBER P271;
FORCEADD UNIVERSAL_GND..1
(-4150 -1975);
FORCEPROP 3 LASTPIN (-4150 -1925) SIG_NAME GND\g
J 0
(-4140 -1915);
DISPLAY 0.659574 (-4140 -1915);
PAINT MONO (-4140 -1915);
DISPLAY INVISIBLE (-4140 -1915);
FORCEPROP 1 LAST HDL_POWER GND
J 1
(-4125 -2050);
DISPLAY 0.872340 (-4125 -2050);
PAINT GREEN (-4125 -2050);
DISPLAY INVISIBLE (-4125 -2050);
FORCEPROP 2 LAST CDS_LIB logical_power
J 0
(-4150 -1975);
PAINT MONO (-4150 -1975);
DISPLAY INVISIBLE (-4150 -1975);
FORCEPROP 1 LAST PATH I1
J 0
(-4075 -1975);
DISPLAY 0.872340 (-4075 -1975);
PAINT AQUA (-4075 -1975);
DISPLAY INVISIBLE (-4075 -1975);
FORCEADD UNIVERSAL_GND..1
(-3650 -1450);
FORCEPROP 3 LASTPIN (-3650 -1400) SIG_NAME GND\g
J 0
(-3640 -1390);
DISPLAY 0.659574 (-3640 -1390);
PAINT MONO (-3640 -1390);
DISPLAY INVISIBLE (-3640 -1390);
FORCEPROP 1 LAST HDL_POWER GND
J 1
(-3625 -1525);
DISPLAY 0.872340 (-3625 -1525);
PAINT GREEN (-3625 -1525);
DISPLAY INVISIBLE (-3625 -1525);
FORCEPROP 2 LAST CDS_LIB logical_power
J 0
(-3650 -1450);
PAINT MONO (-3650 -1450);
DISPLAY INVISIBLE (-3650 -1450);
FORCEPROP 1 LAST PATH I10
J 0
(-3575 -1450);
DISPLAY 0.872340 (-3575 -1450);
PAINT AQUA (-3575 -1450);
DISPLAY INVISIBLE (-3575 -1450);
FORCEADD Q_CAP..1
(-3650 -1200);
FORCEPROP 1 LAST PART_NUMBER CH5222KEB01
J 0
(-3600 -1375);
DISPLAY 0.617021 (-3600 -1375);
PAINT BLUE (-3600 -1375);
DISPLAY INVISIBLE (-3600 -1375);
FORCEPROP 1 LAST PACK_TYPE C0402
J 0
(-3600 -1325);
DISPLAY 0.617021 (-3600 -1325);
PAINT SKYBLUE (-3600 -1325);
FORCEPROP 1 LAST VOLTAGE 10V
J 0
(-3600 -1175);
DISPLAY 0.617021 (-3600 -1175);
PAINT SKYBLUE (-3600 -1175);
FORCEPROP 1 LAST VALUE 2.2UF
J 0
(-3600 -1125);
DISPLAY 0.617021 (-3600 -1125);
PAINT SKYBLUE (-3600 -1125);
FORCEPROP 1 LAST TOLERANCE 10%
J 0
(-3600 -1225);
DISPLAY 0.617021 (-3600 -1225);
PAINT SKYBLUE (-3600 -1225);
FORCEPROP 1 LAST MATERIAL X6S
J 0
(-3600 -1275);
DISPLAY 0.617021 (-3600 -1275);
PAINT SKYBLUE (-3600 -1275);
FORCEPROP 1 LAST LOCATION PC556
J 0
(-3600 -1075);
DISPLAY 0.617021 (-3600 -1075);
PAINT AQUA (-3600 -1075);
FORCEPROP 1 LASTPIN (-3650 -1100) $PN 1
J 0
(-3640 -1120);
DISPLAY 0.617021 (-3640 -1120);
PAINT MONO (-3640 -1120);
FORCEPROP 1 LASTPIN (-3650 -1300) $PN 2
J 0
(-3640 -1320);
DISPLAY 0.617021 (-3640 -1320);
PAINT MONO (-3640 -1320);
FORCEPROP 2 LAST CDS_LIB pure_quanta
J 0
(-3650 -1200);
DISPLAY INVISIBLE (-3650 -1200);
FORCEPROP 1 LAST PATH I11
J 0
(-3600 -1050);
DISPLAY 0.978723 (-3600 -1050);
PAINT WHITE (-3600 -1050);
DISPLAY INVISIBLE (-3600 -1050);
FORCEPROP 1 LAST LOCATION PC556
J 0
(-3600 -1025);
DISPLAY 1.021277 (-3600 -1025);
PAINT AQUA (-3600 -1025);
DISPLAY INVISIBLE (-3600 -1025);
FORCEPROP 0 LAST $SEC 1
J 0
(-3600 -1025);
DISPLAY 0.680851 (-3600 -1025);
PAINT MONO (-3600 -1025);
DISPLAY INVISIBLE (-3600 -1025);
FORCEPROP 0 LAST CDS_SEC 1
J 0
(-3600 -1025);
DISPLAY 1.021277 (-3600 -1025);
DISPLAY INVISIBLE (-3600 -1025);
FORCEADD UNIVERSAL_GND..1
(-3225 -925);
FORCEPROP 3 LASTPIN (-3225 -875) SIG_NAME GND\g
J 0
(-3215 -865);
DISPLAY 0.659574 (-3215 -865);
PAINT MONO (-3215 -865);
DISPLAY INVISIBLE (-3215 -865);
FORCEPROP 1 LAST HDL_POWER GND
J 1
(-3200 -1000);
DISPLAY 0.872340 (-3200 -1000);
PAINT GREEN (-3200 -1000);
DISPLAY INVISIBLE (-3200 -1000);
FORCEPROP 2 LAST CDS_LIB logical_power
J 0
(-3225 -925);
PAINT MONO (-3225 -925);
DISPLAY INVISIBLE (-3225 -925);
FORCEPROP 1 LAST PATH I12
J 0
(-3150 -925);
DISPLAY 0.872340 (-3150 -925);
PAINT AQUA (-3150 -925);
DISPLAY INVISIBLE (-3150 -925);
FORCEADD Q_RES..2
(-3650 -700);
FORCEPROP 1 LAST PART_NUMBER CS-2202FB01
J 0
(-3610 -825);
DISPLAY 0.617021 (-3610 -825);
PAINT BLUE (-3610 -825);
DISPLAY INVISIBLE (-3610 -825);
FORCEPROP 1 LAST PACK_TYPE 0402LF
J 0
(-3610 -875);
DISPLAY 0.617021 (-3610 -875);
PAINT SKYBLUE (-3610 -875);
FORCEPROP 1 LAST TOLERANCE 1%
J 0
(-3605 -675);
DISPLAY 0.617021 (-3605 -675);
PAINT SKYBLUE (-3605 -675);
FORCEPROP 1 LAST MATERIAL CHIP
J 0
(-3610 -775);
DISPLAY 0.617021 (-3610 -775);
PAINT SKYBLUE (-3610 -775);
FORCEPROP 1 LAST WATTAGE 1/16W
J 0
(-3610 -725);
DISPLAY 0.617021 (-3610 -725);
PAINT SKYBLUE (-3610 -725);
FORCEPROP 1 LAST VALUE 2.2
J 0
(-3605 -625);
DISPLAY 0.617021 (-3605 -625);
PAINT SKYBLUE (-3605 -625);
FORCEPROP 1 LAST LOCATION PR327
J 0
(-3605 -575);
DISPLAY 0.617021 (-3605 -575);
PAINT AQUA (-3605 -575);
FORCEPROP 1 LASTPIN (-3650 -600) $PN 1
J 0
(-3645 -638);
DISPLAY 0.617021 (-3645 -638);
PAINT MONO (-3645 -638);
FORCEPROP 1 LASTPIN (-3650 -800) $PN 2
J 0
(-3645 -790);
DISPLAY 0.617021 (-3645 -790);
PAINT MONO (-3645 -790);
FORCEPROP 2 LAST CDS_LIB pure_quanta
J 0
(-3650 -700);
DISPLAY INVISIBLE (-3650 -700);
FORCEPROP 1 LAST PATH I13
J 0
(-3600 -525);
DISPLAY 0.978723 (-3600 -525);
PAINT WHITE (-3600 -525);
DISPLAY INVISIBLE (-3600 -525);
FORCEPROP 1 LAST LOCATION PR327
J 0
(-3600 -525);
DISPLAY 1.021277 (-3600 -525);
PAINT AQUA (-3600 -525);
DISPLAY INVISIBLE (-3600 -525);
FORCEPROP 0 LAST $SEC 1
J 0
(-3600 -525);
DISPLAY 0.680851 (-3600 -525);
PAINT MONO (-3600 -525);
DISPLAY INVISIBLE (-3600 -525);
FORCEPROP 0 LAST CDS_SEC 1
J 0
(-3600 -525);
DISPLAY 1.021277 (-3600 -525);
DISPLAY INVISIBLE (-3600 -525);
FORCEADD VCC15..1
(-3650 -375);
FORCEPROP 3 LASTPIN (-3650 -425) SIG_NAME PVCCIN_CPU1_PVCC\g
J 0
(-3640 -415);
DISPLAY 0.659574 (-3640 -415);
PAINT MONO (-3640 -415);
DISPLAY INVISIBLE (-3640 -415);
FORCEPROP 1 LAST HDL_POWER PVCCIN_CPU1_PVCC
J 1
(-3650 -325);
DISPLAY 0.617021 (-3650 -325);
PAINT GREEN (-3650 -325);
FORCEPROP 2 LAST CDS_LIB logical_power
J 0
(-3650 -375);
DISPLAY INVISIBLE (-3650 -375);
FORCEPROP 1 LAST PATH I14
J 0
(-3600 -350);
DISPLAY 0.872340 (-3600 -350);
PAINT AQUA (-3600 -350);
DISPLAY INVISIBLE (-3600 -350);
FORCEADD Q_CAP..1
(-3225 -700);
FORCEPROP 1 LAST PART_NUMBER CH5222KEB01
J 0
(-3175 -825);
DISPLAY 0.617021 (-3175 -825);
PAINT BLUE (-3175 -825);
DISPLAY INVISIBLE (-3175 -825);
FORCEPROP 1 LAST PACK_TYPE C0402
J 0
(-3175 -875);
DISPLAY 0.617021 (-3175 -875);
PAINT SKYBLUE (-3175 -875);
FORCEPROP 1 LAST VALUE 2.2UF
J 0
(-3175 -625);
DISPLAY 0.617021 (-3175 -625);
PAINT SKYBLUE (-3175 -625);
FORCEPROP 1 LAST TOLERANCE 10%
J 0
(-3175 -725);
DISPLAY 0.617021 (-3175 -725);
PAINT SKYBLUE (-3175 -725);
FORCEPROP 1 LAST MATERIAL X6S
J 0
(-3175 -775);
DISPLAY 0.617021 (-3175 -775);
PAINT SKYBLUE (-3175 -775);
FORCEPROP 1 LAST VOLTAGE 10V
J 0
(-3175 -675);
DISPLAY 0.617021 (-3175 -675);
PAINT SKYBLUE (-3175 -675);
FORCEPROP 1 LAST LOCATION PC558_P1_2
J 0
(-3175 -575);
DISPLAY 0.617021 (-3175 -575);
PAINT AQUA (-3175 -575);
FORCEPROP 1 LASTPIN (-3225 -600) $PN 1
J 0
(-3215 -620);
DISPLAY 0.617021 (-3215 -620);
PAINT MONO (-3215 -620);
FORCEPROP 1 LASTPIN (-3225 -800) $PN 2
J 0
(-3215 -820);
DISPLAY 0.617021 (-3215 -820);
PAINT MONO (-3215 -820);
FORCEPROP 2 LAST CDS_LIB pure_quanta
J 0
(-3225 -700);
DISPLAY INVISIBLE (-3225 -700);
FORCEPROP 1 LAST PATH I15
J 0
(-3175 -550);
DISPLAY 0.978723 (-3175 -550);
PAINT WHITE (-3175 -550);
DISPLAY INVISIBLE (-3175 -550);
FORCEPROP 1 LAST LOCATION PC558_P1_2
J 0
(-3175 -525);
DISPLAY 1.021277 (-3175 -525);
PAINT AQUA (-3175 -525);
DISPLAY INVISIBLE (-3175 -525);
FORCEPROP 0 LAST $SEC 1
J 0
(-3175 -525);
DISPLAY 0.680851 (-3175 -525);
PAINT MONO (-3175 -525);
DISPLAY INVISIBLE (-3175 -525);
FORCEPROP 0 LAST CDS_SEC 1
J 0
(-3175 -525);
DISPLAY 1.021277 (-3175 -525);
DISPLAY INVISIBLE (-3175 -525);
FORCEADD UNIVERSAL_GND..1
(-1475 -2425);
FORCEPROP 3 LASTPIN (-1475 -2375) SIG_NAME GND\g
J 0
(-1465 -2365);
DISPLAY 0.659574 (-1465 -2365);
PAINT MONO (-1465 -2365);
DISPLAY INVISIBLE (-1465 -2365);
FORCEPROP 1 LAST HDL_POWER GND
J 1
(-1450 -2500);
DISPLAY 0.872340 (-1450 -2500);
PAINT GREEN (-1450 -2500);
DISPLAY INVISIBLE (-1450 -2500);
FORCEPROP 2 LAST CDS_LIB logical_power
J 0
(-1475 -2425);
PAINT MONO (-1475 -2425);
DISPLAY INVISIBLE (-1475 -2425);
FORCEPROP 1 LAST PATH I16
J 0
(-1400 -2425);
DISPLAY 0.872340 (-1400 -2425);
PAINT AQUA (-1400 -2425);
DISPLAY INVISIBLE (-1400 -2425);
FORCEADD OFFPAGE..6
(-700 -1950);
FORCEPROP 2 LAST $XR0 286 
J 0
(-980 -1950);
DISPLAY 0.638298 (-980 -1950);
PAINT MONO (-980 -1950);
FORCEPROP 1 LAST COMMENT_BODY TRUE
J 0
(-600 -2025);
DISPLAY 0.872340 (-600 -2025);
PAINT GREEN (-600 -2025);
DISPLAY INVISIBLE (-600 -2025);
FORCEPROP 1 LAST OFFPAGE TRUE
J 0
(-375 -2075);
DISPLAY 0.872340 (-375 -2075);
PAINT GREEN (-375 -2075);
DISPLAY INVISIBLE (-375 -2075);
FORCEPROP 2 LAST CDS_LIB standard
J 0
(-700 -1950);
DISPLAY INVISIBLE (-700 -1950);
FORCEPROP 2 LAST PATH I17
J 0
(-975 -1900);
DISPLAY 1.021277 (-975 -1900);
DISPLAY INVISIBLE (-975 -1900);
FORCEADD Q_INDUCTOR4P_14..1
(300 -1825);
FORCEPROP 1 LAST PART_NUMBER CV+15^0TZ04
J 0
(75 -1665);
DISPLAY 0.617021 (75 -1665);
PAINT BLUE (75 -1665);
DISPLAY INVISIBLE (75 -1665);
FORCEPROP 1 LAST MATERIAL IND
J 0
(75 -1615);
DISPLAY 0.617021 (75 -1615);
PAINT SKYBLUE (75 -1615);
FORCEPROP 2 LAST PART_TYPE SMLF
J 0
(75 -1475);
DISPLAY 1.021277 (75 -1475);
FORCEPROP 2 LAST VALUE 150NH
J 0
(75 -1525);
DISPLAY 0.617021 (75 -1525);
PAINT SKYBLUE (75 -1525);
FORCEPROP 1 LAST LOCATION PL30
J 0
(75 -1570);
DISPLAY 0.617021 (75 -1570);
PAINT AQUA (75 -1570);
FORCEPROP 2 LASTPIN (-100 -1700) $PN 1
J 2
(-110 -1690);
DISPLAY 0.617021 (-110 -1690);
PAINT MONO (-110 -1690);
FORCEPROP 2 LASTPIN (-100 -1950) $PN 2
J 2
(-110 -1940);
DISPLAY 0.617021 (-110 -1940);
PAINT MONO (-110 -1940);
FORCEPROP 2 LASTPIN (700 -1950) $PN 3
J 0
(710 -1940);
DISPLAY 0.617021 (710 -1940);
PAINT MONO (710 -1940);
FORCEPROP 2 LASTPIN (700 -1700) $PN 4
J 0
(710 -1690);
DISPLAY 0.617021 (710 -1690);
PAINT MONO (710 -1690);
FORCEPROP 2 LAST SEC_TYPE 
J 0
(75 -1425);
DISPLAY 1.021277 (75 -1425);
DISPLAY INVISIBLE (75 -1425);
FORCEPROP 2 LAST CDS_LIB pure_quanta
J 0
(300 -1825);
DISPLAY INVISIBLE (300 -1825);
FORCEPROP 1 LAST NEEDS_NO_SIZE TRUE
J 0
(300 -1825);
DISPLAY 0.468085 (300 -1825);
PAINT GREEN (300 -1825);
DISPLAY INVISIBLE (300 -1825);
FORCEPROP 1 LAST PATH I18
J 0
(500 -1670);
DISPLAY 0.723404 (500 -1670);
PAINT GREEN (500 -1670);
DISPLAY INVISIBLE (500 -1670);
FORCEPROP 2 LAST SEC 1
J 0
(75 -1425);
DISPLAY 0.680851 (75 -1425);
PAINT MONO (75 -1425);
DISPLAY INVISIBLE (75 -1425);
FORCEADD Q_CAP..1
(-1325 -800);
FORCEPROP 1 LAST PART_NUMBER TMP_QCH2336K1B12
J 0
(-1275 -950);
DISPLAY 0.617021 (-1275 -950);
PAINT BLUE (-1275 -950);
DISPLAY INVISIBLE (-1275 -950);
FORCEPROP 1 LAST PACK_TYPE 0402
J 0
(-1275 -900);
DISPLAY 0.617021 (-1275 -900);
PAINT SKYBLUE (-1275 -900);
FORCEPROP 1 LAST VOLTAGE 50V
J 0
(-1275 -750);
DISPLAY 0.617021 (-1275 -750);
PAINT SKYBLUE (-1275 -750);
FORCEPROP 1 LAST VALUE 3300PF
J 0
(-1275 -700);
DISPLAY 0.617021 (-1275 -700);
PAINT SKYBLUE (-1275 -700);
FORCEPROP 1 LAST TOLERANCE 10%
J 0
(-1275 -800);
DISPLAY 0.617021 (-1275 -800);
PAINT SKYBLUE (-1275 -800);
FORCEPROP 1 LAST MATERIAL X7R
J 0
(-1275 -850);
DISPLAY 0.617021 (-1275 -850);
PAINT SKYBLUE (-1275 -850);
FORCEPROP 1 LAST LOCATION PC560_P1_2
J 0
(-1275 -650);
DISPLAY 0.617021 (-1275 -650);
PAINT AQUA (-1275 -650);
FORCEPROP 1 LASTPIN (-1325 -700) $PN 1
J 0
(-1315 -720);
DISPLAY 0.617021 (-1315 -720);
PAINT MONO (-1315 -720);
FORCEPROP 1 LASTPIN (-1325 -900) $PN 2
J 0
(-1315 -920);
DISPLAY 0.617021 (-1315 -920);
PAINT MONO (-1315 -920);
FORCEPROP 2 LAST CDS_LIB pure_quanta
J 0
(-1325 -800);
DISPLAY INVISIBLE (-1325 -800);
FORCEPROP 1 LAST PATH I19
J 0
(-1275 -650);
DISPLAY 0.978723 (-1275 -650);
PAINT WHITE (-1275 -650);
DISPLAY INVISIBLE (-1275 -650);
FORCEPROP 1 LAST LOCATION PC560_P1_2
J 0
(-1275 -600);
DISPLAY 1.021277 (-1275 -600);
PAINT AQUA (-1275 -600);
DISPLAY INVISIBLE (-1275 -600);
FORCEPROP 0 LAST $SEC 1
J 0
(-1275 -600);
DISPLAY 0.680851 (-1275 -600);
PAINT MONO (-1275 -600);
DISPLAY INVISIBLE (-1275 -600);
FORCEPROP 0 LAST CDS_SEC 1
J 0
(-1275 -600);
DISPLAY 1.021277 (-1275 -600);
DISPLAY INVISIBLE (-1275 -600);
FORCEADD UNIVERSAL_GND..1
(-4050 -2425);
FORCEPROP 3 LASTPIN (-4050 -2375) SIG_NAME GND\g
J 0
(-4040 -2365);
DISPLAY 0.659574 (-4040 -2365);
PAINT MONO (-4040 -2365);
DISPLAY INVISIBLE (-4040 -2365);
FORCEPROP 1 LAST HDL_POWER GND
J 1
(-4025 -2500);
DISPLAY 0.872340 (-4025 -2500);
PAINT GREEN (-4025 -2500);
DISPLAY INVISIBLE (-4025 -2500);
FORCEPROP 2 LAST CDS_LIB logical_power
J 0
(-4050 -2425);
PAINT MONO (-4050 -2425);
DISPLAY INVISIBLE (-4050 -2425);
FORCEPROP 1 LAST PATH I2
J 0
(-3975 -2425);
DISPLAY 0.872340 (-3975 -2425);
PAINT AQUA (-3975 -2425);
DISPLAY INVISIBLE (-3975 -2425);
FORCEADD Q_RES..1
(-875 -1250);
FORCEPROP 1 LAST PART_NUMBER CS-3302FB01
J 0
(-975 -1200);
DISPLAY 0.617021 (-975 -1200);
PAINT BLUE (-975 -1200);
DISPLAY INVISIBLE (-975 -1200);
FORCEPROP 1 LAST MATERIAL CHIP
J 0
(-975 -1150);
DISPLAY 0.617021 (-975 -1150);
PAINT SKYBLUE (-975 -1150);
FORCEPROP 1 LAST PACK_TYPE 0402LF
J 0
(-975 -1175);
DISPLAY 0.617021 (-975 -1175);
PAINT SKYBLUE (-975 -1175);
FORCEPROP 1 LAST VALUE 3.3
J 2
(-750 -1250);
DISPLAY 0.617021 (-750 -1250);
PAINT SKYBLUE (-750 -1250);
FORCEPROP 1 LAST WATTAGE 1/16W
J 2
(-625 -1175);
DISPLAY 0.617021 (-625 -1175);
PAINT SKYBLUE (-625 -1175);
FORCEPROP 1 LAST TOLERANCE 1%
J 0
(-725 -1250);
DISPLAY 0.617021 (-725 -1250);
PAINT SKYBLUE (-725 -1250);
FORCEPROP 1 LAST LOCATION PR1766
J 0
(-1075 -1250);
DISPLAY 0.617021 (-1075 -1250);
PAINT AQUA (-1075 -1250);
FORCEPROP 1 LASTPIN (-975 -1250) $PN 1
J 0
(-963 -1238);
DISPLAY 0.617021 (-963 -1238);
FORCEPROP 1 LASTPIN (-775 -1250) $PN 2
J 0
(-813 -1238);
DISPLAY 0.617021 (-813 -1238);
FORCEPROP 2 LAST CDS_LIB pure_quanta
J 0
(-875 -1250);
PAINT MONO (-875 -1250);
DISPLAY INVISIBLE (-875 -1250);
FORCEPROP 1 LAST PATH I20
J 0
(-925 -1100);
DISPLAY 0.978723 (-925 -1100);
PAINT WHITE (-925 -1100);
DISPLAY INVISIBLE (-925 -1100);
FORCEPROP 2 LAST $SEC 1
J 0
(-925 -1050);
DISPLAY 0.680851 (-925 -1050);
PAINT MONO (-925 -1050);
DISPLAY INVISIBLE (-925 -1050);
FORCEPROP 2 LAST CDS_SEC 1
J 0
(-925 -1050);
DISPLAY 1.021277 (-925 -1050);
DISPLAY INVISIBLE (-925 -1050);
FORCEADD Q_CAP..1
(-925 -800);
FORCEPROP 1 LAST PART_NUMBER CH5103KEB01
J 0
(-875 -950);
DISPLAY 0.617021 (-875 -950);
PAINT BLUE (-875 -950);
DISPLAY INVISIBLE (-875 -950);
FORCEPROP 1 LAST VOLTAGE 16V
J 0
(-875 -750);
DISPLAY 0.617021 (-875 -750);
PAINT SKYBLUE (-875 -750);
FORCEPROP 1 LAST VALUE 1UF
J 0
(-875 -700);
DISPLAY 0.617021 (-875 -700);
PAINT SKYBLUE (-875 -700);
FORCEPROP 1 LAST TOLERANCE 10%
J 0
(-875 -800);
DISPLAY 0.617021 (-875 -800);
PAINT SKYBLUE (-875 -800);
FORCEPROP 1 LAST MATERIAL X6S
J 0
(-875 -850);
DISPLAY 0.617021 (-875 -850);
PAINT SKYBLUE (-875 -850);
FORCEPROP 1 LAST PACK_TYPE C0402
J 0
(-875 -900);
DISPLAY 0.617021 (-875 -900);
PAINT SKYBLUE (-875 -900);
FORCEPROP 1 LAST LOCATION PC562_P1_2
J 0
(-875 -650);
DISPLAY 0.617021 (-875 -650);
PAINT AQUA (-875 -650);
FORCEPROP 1 LASTPIN (-925 -700) $PN 1
J 0
(-915 -720);
DISPLAY 0.617021 (-915 -720);
PAINT MONO (-915 -720);
FORCEPROP 1 LASTPIN (-925 -900) $PN 2
J 0
(-915 -920);
DISPLAY 0.617021 (-915 -920);
PAINT MONO (-915 -920);
FORCEPROP 2 LAST CDS_LIB pure_quanta
J 0
(-925 -800);
DISPLAY INVISIBLE (-925 -800);
FORCEPROP 1 LAST PATH I21
J 0
(-875 -650);
DISPLAY 0.978723 (-875 -650);
PAINT WHITE (-875 -650);
DISPLAY INVISIBLE (-875 -650);
FORCEPROP 1 LAST LOCATION PC562_P1_2
J 0
(-875 -600);
DISPLAY 1.021277 (-875 -600);
PAINT AQUA (-875 -600);
DISPLAY INVISIBLE (-875 -600);
FORCEPROP 0 LAST $SEC 1
J 0
(-875 -600);
DISPLAY 0.680851 (-875 -600);
PAINT MONO (-875 -600);
DISPLAY INVISIBLE (-875 -600);
FORCEPROP 0 LAST CDS_SEC 1
J 0
(-875 -600);
DISPLAY 1.021277 (-875 -600);
DISPLAY INVISIBLE (-875 -600);
FORCEADD Q_CAP..1
(-525 -800);
FORCEPROP 1 LAST PART_NUMBER CH6223MEA01
J 0
(-475 -950);
DISPLAY 0.617021 (-475 -950);
PAINT BLUE (-475 -950);
DISPLAY INVISIBLE (-475 -950);
FORCEPROP 1 LAST TOLERANCE 20%
J 0
(-475 -800);
DISPLAY 0.617021 (-475 -800);
PAINT SKYBLUE (-475 -800);
FORCEPROP 1 LAST PACK_TYPE C0805
J 0
(-475 -900);
DISPLAY 0.617021 (-475 -900);
PAINT SKYBLUE (-475 -900);
FORCEPROP 1 LAST VOLTAGE 16V
J 0
(-475 -750);
DISPLAY 0.617021 (-475 -750);
PAINT SKYBLUE (-475 -750);
FORCEPROP 1 LAST VALUE 22UF
J 0
(-475 -700);
DISPLAY 0.617021 (-475 -700);
PAINT SKYBLUE (-475 -700);
FORCEPROP 1 LAST MATERIAL X6S
J 0
(-475 -850);
DISPLAY 0.617021 (-475 -850);
PAINT SKYBLUE (-475 -850);
FORCEPROP 1 LAST LOCATION PC566_P1_2
J 0
(-475 -650);
DISPLAY 0.617021 (-475 -650);
PAINT AQUA (-475 -650);
FORCEPROP 1 LASTPIN (-525 -700) $PN 1
J 0
(-515 -720);
DISPLAY 0.617021 (-515 -720);
PAINT MONO (-515 -720);
FORCEPROP 1 LASTPIN (-525 -900) $PN 2
J 0
(-515 -920);
DISPLAY 0.617021 (-515 -920);
PAINT MONO (-515 -920);
FORCEPROP 2 LAST CDS_LIB pure_quanta
J 0
(-525 -800);
DISPLAY INVISIBLE (-525 -800);
FORCEPROP 1 LAST PATH I22
J 0
(-475 -650);
DISPLAY 0.978723 (-475 -650);
PAINT WHITE (-475 -650);
DISPLAY INVISIBLE (-475 -650);
FORCEPROP 1 LAST LOCATION PC566_P1_2
J 0
(-475 -600);
DISPLAY 1.021277 (-475 -600);
PAINT AQUA (-475 -600);
DISPLAY INVISIBLE (-475 -600);
FORCEPROP 0 LAST $SEC 1
J 0
(-475 -600);
DISPLAY 0.680851 (-475 -600);
PAINT MONO (-475 -600);
DISPLAY INVISIBLE (-475 -600);
FORCEPROP 0 LAST CDS_SEC 1
J 0
(-475 -600);
DISPLAY 1.021277 (-475 -600);
DISPLAY INVISIBLE (-475 -600);
FORCEADD Q_CAP..1
R 2
(-150 -1425);
FORCEPROP 1 LAST PART_NUMBER CH4106K1B01
J 2
(-200 -1525);
DISPLAY 0.617021 (-200 -1525);
PAINT BLUE (-200 -1525);
DISPLAY INVISIBLE (-200 -1525);
FORCEPROP 1 LAST PACK_TYPE C0402
J 2
(-200 -1500);
DISPLAY 0.617021 (-200 -1500);
PAINT SKYBLUE (-200 -1500);
FORCEPROP 1 LAST MATERIAL X7R
J 2
(-200 -1475);
DISPLAY 0.617021 (-200 -1475);
PAINT SKYBLUE (-200 -1475);
FORCEPROP 1 LAST VOLTAGE 50V
J 2
(-200 -1425);
DISPLAY 0.617021 (-200 -1425);
PAINT SKYBLUE (-200 -1425);
FORCEPROP 1 LAST TOLERANCE 10%
J 2
(-200 -1450);
DISPLAY 0.617021 (-200 -1450);
PAINT SKYBLUE (-200 -1450);
FORCEPROP 1 LAST VALUE 100NF
J 2
(-200 -1400);
DISPLAY 0.617021 (-200 -1400);
PAINT SKYBLUE (-200 -1400);
FORCEPROP 1 LAST LOCATION PC564
J 2
(-200 -1375);
DISPLAY 0.617021 (-200 -1375);
PAINT AQUA (-200 -1375);
FORCEPROP 1 LASTPIN (-150 -1325) $PN 1
J 2
(-160 -1345);
DISPLAY 0.617021 (-160 -1345);
PAINT MONO (-160 -1345);
FORCEPROP 1 LASTPIN (-150 -1525) $PN 2
J 2
(-160 -1545);
DISPLAY 0.617021 (-160 -1545);
PAINT MONO (-160 -1545);
FORCEPROP 2 LAST CDS_LIB pure_quanta
J 2
(-150 -1425);
DISPLAY INVISIBLE (-150 -1425);
FORCEPROP 1 LAST PATH I23
J 2
(-200 -1275);
DISPLAY 0.978723 (-200 -1275);
PAINT WHITE (-200 -1275);
DISPLAY INVISIBLE (-200 -1275);
FORCEPROP 1 LAST LOCATION PC564
J 2
(-200 -1225);
DISPLAY 1.021277 (-200 -1225);
PAINT AQUA (-200 -1225);
DISPLAY INVISIBLE (-200 -1225);
FORCEPROP 0 LAST $SEC 1
J 2
(-200 -1225);
DISPLAY 0.680851 (-200 -1225);
PAINT MONO (-200 -1225);
DISPLAY INVISIBLE (-200 -1225);
FORCEPROP 0 LAST CDS_SEC 1
J 2
(-200 -1225);
DISPLAY 1.021277 (-200 -1225);
DISPLAY INVISIBLE (-200 -1225);
FORCEADD Q_CAP..1
(-125 -800);
FORCEPROP 1 LAST PART_NUMBER CH6223MEA01
J 0
(-75 -950);
DISPLAY 0.617021 (-75 -950);
PAINT BLUE (-75 -950);
DISPLAY INVISIBLE (-75 -950);
FORCEPROP 1 LAST TOLERANCE 20%
J 0
(-75 -800);
DISPLAY 0.617021 (-75 -800);
PAINT SKYBLUE (-75 -800);
FORCEPROP 1 LAST MATERIAL X6S
J 0
(-75 -850);
DISPLAY 0.617021 (-75 -850);
PAINT SKYBLUE (-75 -850);
FORCEPROP 1 LAST PACK_TYPE C0805
J 0
(-75 -900);
DISPLAY 0.617021 (-75 -900);
PAINT SKYBLUE (-75 -900);
FORCEPROP 1 LAST VOLTAGE 16V
J 0
(-75 -750);
DISPLAY 0.617021 (-75 -750);
PAINT SKYBLUE (-75 -750);
FORCEPROP 1 LAST VALUE 22UF
J 0
(-75 -700);
DISPLAY 0.617021 (-75 -700);
PAINT SKYBLUE (-75 -700);
FORCEPROP 1 LAST LOCATION PC568_P1_2
J 0
(-75 -650);
DISPLAY 0.617021 (-75 -650);
PAINT AQUA (-75 -650);
FORCEPROP 1 LASTPIN (-125 -700) $PN 1
J 0
(-115 -720);
DISPLAY 0.617021 (-115 -720);
PAINT MONO (-115 -720);
FORCEPROP 1 LASTPIN (-125 -900) $PN 2
J 0
(-115 -920);
DISPLAY 0.617021 (-115 -920);
PAINT MONO (-115 -920);
FORCEPROP 2 LAST CDS_LIB pure_quanta
J 0
(-125 -800);
DISPLAY INVISIBLE (-125 -800);
FORCEPROP 1 LAST PATH I24
J 0
(-75 -650);
DISPLAY 0.978723 (-75 -650);
PAINT WHITE (-75 -650);
DISPLAY INVISIBLE (-75 -650);
FORCEPROP 1 LAST LOCATION PC568_P1_2
J 0
(-75 -600);
DISPLAY 1.021277 (-75 -600);
PAINT AQUA (-75 -600);
DISPLAY INVISIBLE (-75 -600);
FORCEPROP 0 LAST $SEC 1
J 0
(-75 -600);
DISPLAY 0.680851 (-75 -600);
PAINT MONO (-75 -600);
DISPLAY INVISIBLE (-75 -600);
FORCEPROP 0 LAST CDS_SEC 1
J 0
(-75 -600);
DISPLAY 1.021277 (-75 -600);
DISPLAY INVISIBLE (-75 -600);
FORCEADD UNIVERSAL_GND..1
(-4125 850);
FORCEPROP 3 LASTPIN (-4125 900) SIG_NAME GND\g
J 0
(-4115 910);
DISPLAY 0.659574 (-4115 910);
PAINT MONO (-4115 910);
DISPLAY INVISIBLE (-4115 910);
FORCEPROP 1 LAST HDL_POWER GND
J 1
(-4100 775);
DISPLAY 0.872340 (-4100 775);
PAINT GREEN (-4100 775);
DISPLAY INVISIBLE (-4100 775);
FORCEPROP 2 LAST CDS_LIB logical_power
J 0
(-4125 850);
PAINT MONO (-4125 850);
DISPLAY INVISIBLE (-4125 850);
FORCEPROP 1 LAST PATH I25
J 0
(-4050 850);
DISPLAY 0.872340 (-4050 850);
PAINT AQUA (-4050 850);
DISPLAY INVISIBLE (-4050 850);
FORCEADD Q_RES..2
(-4125 2800);
FORCEPROP 1 LAST PART_NUMBER CS00002JB13
J 0
(-4085 2675);
DISPLAY 0.617021 (-4085 2675);
PAINT BLUE (-4085 2675);
DISPLAY INVISIBLE (-4085 2675);
FORCEPROP 1 LAST PACK_TYPE 0402LF
J 0
(-4085 2625);
DISPLAY 0.617021 (-4085 2625);
PAINT SKYBLUE (-4085 2625);
FORCEPROP 1 LAST VALUE 0
J 0
(-4080 2875);
DISPLAY 0.617021 (-4080 2875);
PAINT SKYBLUE (-4080 2875);
FORCEPROP 1 LAST TOLERANCE 5%
J 0
(-4080 2825);
DISPLAY 0.617021 (-4080 2825);
PAINT SKYBLUE (-4080 2825);
FORCEPROP 1 LAST MATERIAL CHIP
J 0
(-4085 2725);
DISPLAY 0.617021 (-4085 2725);
PAINT SKYBLUE (-4085 2725);
FORCEPROP 1 LAST WATTAGE 1/16W
J 0
(-4085 2775);
DISPLAY 0.617021 (-4085 2775);
PAINT SKYBLUE (-4085 2775);
FORCEPROP 1 LAST LOCATION PR639
J 0
(-4080 2925);
DISPLAY 0.617021 (-4080 2925);
PAINT AQUA (-4080 2925);
FORCEPROP 2 LAST CDS_LIB pure_quanta
J 0
(-4125 2800);
DISPLAY INVISIBLE (-4125 2800);
FORCEPROP 1 LAST PATH I26
J 0
(-4075 2975);
DISPLAY 0.978723 (-4075 2975);
PAINT WHITE (-4075 2975);
DISPLAY INVISIBLE (-4075 2975);
FORCEPROP 0 LAST $SEC 1
J 0
(-4075 2975);
DISPLAY INVISIBLE (-4075 2975);
FORCEPROP 0 LAST CDS_SEC 1
J 0
(-4075 2975);
DISPLAY INVISIBLE (-4075 2975);
FORCEPROP 1 LASTPIN (-4125 2900) $PN 1
J 0
(-4120 2862);
DISPLAY 0.787234 (-4120 2862);
PAINT MONO (-4120 2862);
DISPLAY INVISIBLE (-4120 2862);
FORCEPROP 1 LASTPIN (-4125 2700) $PN 2
J 0
(-4120 2710);
DISPLAY 0.787234 (-4120 2710);
PAINT MONO (-4120 2710);
DISPLAY INVISIBLE (-4120 2710);
FORCEADD VCC15..1
(-4125 3025);
FORCEPROP 3 LASTPIN (-4125 2975) SIG_NAME P5V\g
J 0
(-4115 2985);
DISPLAY 0.659574 (-4115 2985);
PAINT MONO (-4115 2985);
DISPLAY INVISIBLE (-4115 2985);
FORCEPROP 1 LAST HDL_POWER P5V
J 1
(-4125 3075);
DISPLAY 0.617021 (-4125 3075);
PAINT GREEN (-4125 3075);
FORCEPROP 2 LAST CDS_LIB logical_power
J 0
(-4125 3025);
DISPLAY INVISIBLE (-4125 3025);
FORCEPROP 1 LAST PATH I27
J 0
(-4075 3050);
DISPLAY 0.872340 (-4075 3050);
PAINT AQUA (-4075 3050);
DISPLAY INVISIBLE (-4075 3050);
FORCEADD UNIVERSAL_GND..1
(-4025 400);
FORCEPROP 3 LASTPIN (-4025 450) SIG_NAME GND\g
J 0
(-4015 460);
DISPLAY 0.659574 (-4015 460);
PAINT MONO (-4015 460);
DISPLAY INVISIBLE (-4015 460);
FORCEPROP 1 LAST HDL_POWER GND
J 1
(-4000 325);
DISPLAY 0.872340 (-4000 325);
PAINT GREEN (-4000 325);
DISPLAY INVISIBLE (-4000 325);
FORCEPROP 2 LAST CDS_LIB logical_power
J 0
(-4025 400);
PAINT MONO (-4025 400);
DISPLAY INVISIBLE (-4025 400);
FORCEPROP 1 LAST PATH I28
J 0
(-3950 400);
DISPLAY 0.872340 (-3950 400);
PAINT AQUA (-3950 400);
DISPLAY INVISIBLE (-3950 400);
FORCEADD Q_RES..2
R 2
(-4025 625);
FORCEPROP 1 LAST PART_NUMBER CS28872FB01
J 2
(-4075 500);
DISPLAY 0.617021 (-4075 500);
PAINT BLUE (-4075 500);
DISPLAY INVISIBLE (-4075 500);
FORCEPROP 1 LAST PACK_TYPE 0402LF
J 2
(-4075 450);
DISPLAY 0.617021 (-4075 450);
PAINT SKYBLUE (-4075 450);
FORCEPROP 1 LAST VALUE 8.87K
J 2
(-4080 700);
DISPLAY 0.617021 (-4080 700);
PAINT SKYBLUE (-4080 700);
FORCEPROP 1 LAST TOLERANCE 1%
J 2
(-4080 650);
DISPLAY 0.617021 (-4080 650);
PAINT SKYBLUE (-4080 650);
FORCEPROP 1 LAST MATERIAL EMPTY
J 2
(-4075 550);
DISPLAY 0.617021 (-4075 550);
PAINT RED (-4075 550);
FORCEPROP 1 LAST WATTAGE 1/16W
J 2
(-4075 600);
DISPLAY 0.617021 (-4075 600);
PAINT SKYBLUE (-4075 600);
FORCEPROP 1 LAST LOCATION PR326
J 2
(-4070 750);
DISPLAY 0.617021 (-4070 750);
PAINT AQUA (-4070 750);
FORCEPROP 1 LASTPIN (-4025 725) $PN 1
J 2
(-4030 687);
DISPLAY 0.617021 (-4030 687);
PAINT MONO (-4030 687);
FORCEPROP 1 LASTPIN (-4025 525) $PN 2
J 2
(-4030 535);
DISPLAY 0.617021 (-4030 535);
PAINT MONO (-4030 535);
FORCEPROP 2 LAST CDS_LIB pure_quanta
J 2
(-4025 625);
DISPLAY INVISIBLE (-4025 625);
FORCEPROP 1 LAST PATH I29
J 2
(-4075 800);
DISPLAY 0.978723 (-4075 800);
PAINT WHITE (-4075 800);
DISPLAY INVISIBLE (-4075 800);
FORCEPROP 1 LAST LOCATION PR326
J 2
(-4075 800);
DISPLAY 1.021277 (-4075 800);
PAINT AQUA (-4075 800);
DISPLAY INVISIBLE (-4075 800);
FORCEPROP 0 LAST $SEC 1
J 2
(-4075 800);
DISPLAY 0.680851 (-4075 800);
PAINT MONO (-4075 800);
DISPLAY INVISIBLE (-4075 800);
FORCEPROP 0 LAST CDS_SEC 1
J 2
(-4075 800);
DISPLAY 1.021277 (-4075 800);
DISPLAY INVISIBLE (-4075 800);
FORCEADD Q_RES..2
R 2
(-4050 -2200);
FORCEPROP 1 LAST PART_NUMBER CS28872FB01
J 2
(-4100 -2325);
DISPLAY 0.617021 (-4100 -2325);
PAINT BLUE (-4100 -2325);
DISPLAY INVISIBLE (-4100 -2325);
FORCEPROP 1 LAST PACK_TYPE 0402LF
J 2
(-4100 -2375);
DISPLAY 0.617021 (-4100 -2375);
PAINT SKYBLUE (-4100 -2375);
FORCEPROP 1 LAST VALUE 8.87K
J 2
(-4105 -2125);
DISPLAY 0.617021 (-4105 -2125);
PAINT SKYBLUE (-4105 -2125);
FORCEPROP 1 LAST TOLERANCE 1%
J 2
(-4105 -2175);
DISPLAY 0.617021 (-4105 -2175);
PAINT SKYBLUE (-4105 -2175);
FORCEPROP 1 LAST MATERIAL EMPTY
J 2
(-4100 -2275);
DISPLAY 0.617021 (-4100 -2275);
PAINT RED (-4100 -2275);
FORCEPROP 1 LAST WATTAGE 1/16W
J 2
(-4100 -2225);
DISPLAY 0.617021 (-4100 -2225);
PAINT SKYBLUE (-4100 -2225);
FORCEPROP 1 LAST LOCATION PR325
J 2
(-4095 -2075);
DISPLAY 0.617021 (-4095 -2075);
PAINT AQUA (-4095 -2075);
FORCEPROP 1 LASTPIN (-4050 -2100) $PN 1
J 2
(-4055 -2138);
DISPLAY 0.617021 (-4055 -2138);
PAINT MONO (-4055 -2138);
FORCEPROP 1 LASTPIN (-4050 -2300) $PN 2
J 2
(-4055 -2290);
DISPLAY 0.617021 (-4055 -2290);
PAINT MONO (-4055 -2290);
FORCEPROP 2 LAST CDS_LIB pure_quanta
J 2
(-4050 -2200);
DISPLAY INVISIBLE (-4050 -2200);
FORCEPROP 1 LAST PATH I3
J 2
(-4100 -2025);
DISPLAY 0.978723 (-4100 -2025);
PAINT WHITE (-4100 -2025);
DISPLAY INVISIBLE (-4100 -2025);
FORCEPROP 1 LAST LOCATION PR325
J 2
(-4100 -2025);
DISPLAY 1.021277 (-4100 -2025);
PAINT AQUA (-4100 -2025);
DISPLAY INVISIBLE (-4100 -2025);
FORCEPROP 0 LAST $SEC 1
J 2
(-4100 -2025);
DISPLAY 0.680851 (-4100 -2025);
PAINT MONO (-4100 -2025);
DISPLAY INVISIBLE (-4100 -2025);
FORCEPROP 0 LAST CDS_SEC 1
J 2
(-4100 -2025);
DISPLAY 1.021277 (-4100 -2025);
DISPLAY INVISIBLE (-4100 -2025);
FORCEADD OFFPAGE..1
(-3550 525);
FORCEPROP 2 LAST $XR0 284 
J 0
(-3802 525);
DISPLAY 0.638298 (-3802 525);
PAINT MONO (-3802 525);
FORCEPROP 1 LAST COMMENT_BODY TRUE
J 0
(-3425 425);
DISPLAY 0.872340 (-3425 425);
PAINT GREEN (-3425 425);
DISPLAY INVISIBLE (-3425 425);
FORCEPROP 1 LAST OFFPAGE TRUE
J 0
(-3225 400);
DISPLAY 0.872340 (-3225 400);
PAINT GREEN (-3225 400);
DISPLAY INVISIBLE (-3225 400);
FORCEPROP 2 LAST CDS_LIB standard
J 0
(-3550 525);
DISPLAY INVISIBLE (-3550 525);
FORCEPROP 2 LAST PATH I30
J 0
(-3975 575);
DISPLAY 1.021277 (-3975 575);
DISPLAY INVISIBLE (-3975 575);
FORCEADD OFFPAGE..5
(-3550 625);
FORCEPROP 2 LAST $XR4 284 
J 0
(-3805 733);
DISPLAY 0.638298 (-3805 733);
PAINT MONO (-3805 733);
FORCEPROP 2 LAST $XR3 288 
J 0
(-3805 697);
DISPLAY 0.638298 (-3805 697);
PAINT MONO (-3805 697);
FORCEPROP 2 LAST $XR2 287 
J 0
(-3805 661);
DISPLAY 0.638298 (-3805 661);
PAINT MONO (-3805 661);
FORCEPROP 2 LAST $XR1 286 
J 0
(-3805 589);
DISPLAY 0.638298 (-3805 589);
PAINT MONO (-3805 589);
FORCEPROP 2 LAST $XR0 285 
J 0
(-3805 625);
DISPLAY 0.638298 (-3805 625);
PAINT MONO (-3805 625);
FORCEPROP 1 LAST COMMENT_BODY TRUE
J 0
(-3450 550);
DISPLAY 0.872340 (-3450 550);
PAINT GREEN (-3450 550);
DISPLAY INVISIBLE (-3450 550);
FORCEPROP 1 LAST OFFPAGE TRUE
J 0
(-3225 500);
DISPLAY 0.872340 (-3225 500);
PAINT GREEN (-3225 500);
DISPLAY INVISIBLE (-3225 500);
FORCEPROP 2 LAST CDS_LIB standard
J 0
(-3550 625);
DISPLAY INVISIBLE (-3550 625);
FORCEPROP 2 LAST PATH I31
J 0
(-3800 750);
DISPLAY 1.021277 (-3800 750);
DISPLAY INVISIBLE (-3800 750);
FORCEADD OFFPAGE..1
(-3550 1025);
FORCEPROP 2 LAST $XR6 290 
J 0
(-4522 1025);
DISPLAY 0.638298 (-4522 1025);
PAINT MONO (-4522 1025);
FORCEPROP 2 LAST $XR5 289 
J 0
(-4402 1025);
DISPLAY 0.638298 (-4402 1025);
PAINT MONO (-4402 1025);
FORCEPROP 2 LAST $XR4 288 
J 0
(-4282 1025);
DISPLAY 0.638298 (-4282 1025);
PAINT MONO (-4282 1025);
FORCEPROP 2 LAST $XR3 287 
J 0
(-4162 1025);
DISPLAY 0.638298 (-4162 1025);
PAINT MONO (-4162 1025);
FORCEPROP 2 LAST $XR2 286 
J 0
(-4042 1025);
DISPLAY 0.638298 (-4042 1025);
PAINT MONO (-4042 1025);
FORCEPROP 2 LAST $XR1 285 
J 0
(-3922 1025);
DISPLAY 0.638298 (-3922 1025);
PAINT MONO (-3922 1025);
FORCEPROP 2 LAST $XR0 284 
J 0
(-3802 1025);
DISPLAY 0.638298 (-3802 1025);
PAINT MONO (-3802 1025);
FORCEPROP 1 LAST COMMENT_BODY TRUE
J 0
(-3425 925);
DISPLAY 0.872340 (-3425 925);
PAINT GREEN (-3425 925);
DISPLAY INVISIBLE (-3425 925);
FORCEPROP 1 LAST OFFPAGE TRUE
J 0
(-3225 900);
DISPLAY 0.872340 (-3225 900);
PAINT GREEN (-3225 900);
DISPLAY INVISIBLE (-3225 900);
FORCEPROP 2 LAST CDS_LIB standard
J 0
(-3550 1025);
DISPLAY INVISIBLE (-3550 1025);
FORCEPROP 2 LAST PATH I32
J 0
(-3800 1075);
DISPLAY 1.021277 (-3800 1075);
DISPLAY INVISIBLE (-3800 1075);
FORCEADD OFFPAGE..5
(-3550 1125);
FORCEPROP 2 LAST $XR0 284 
J 0
(-3805 1125);
DISPLAY 0.638298 (-3805 1125);
PAINT MONO (-3805 1125);
FORCEPROP 1 LAST COMMENT_BODY TRUE
J 0
(-3450 1050);
DISPLAY 0.872340 (-3450 1050);
PAINT GREEN (-3450 1050);
DISPLAY INVISIBLE (-3450 1050);
FORCEPROP 1 LAST OFFPAGE TRUE
J 0
(-3225 1000);
DISPLAY 0.872340 (-3225 1000);
PAINT GREEN (-3225 1000);
DISPLAY INVISIBLE (-3225 1000);
FORCEPROP 2 LAST CDS_LIB standard
J 0
(-3550 1125);
DISPLAY INVISIBLE (-3550 1125);
FORCEPROP 2 LAST PATH I33
J 0
(-3800 1175);
DISPLAY 1.021277 (-3800 1175);
DISPLAY INVISIBLE (-3800 1175);
FORCEADD Q_CAP..2
(-3300 925);
FORCEPROP 1 LAST PART_NUMBER CH4104K1B00
J 1
(-3075 975);
DISPLAY 0.617021 (-3075 975);
PAINT BLUE (-3075 975);
DISPLAY INVISIBLE (-3075 975);
FORCEPROP 1 LAST TOLERANCE 10%
J 2
(-2675 975);
DISPLAY 0.617021 (-2675 975);
PAINT SKYBLUE (-2675 975);
FORCEPROP 1 LAST MATERIAL X7R
J 0
(-2875 975);
DISPLAY 0.617021 (-2875 975);
PAINT SKYBLUE (-2875 975);
FORCEPROP 1 LAST VALUE 0.1UF
J 2
(-3025 925);
DISPLAY 0.617021 (-3025 925);
PAINT SKYBLUE (-3025 925);
FORCEPROP 1 LAST VOLTAGE 25V
J 0
(-3000 925);
DISPLAY 0.617021 (-3000 925);
PAINT SKYBLUE (-3000 925);
FORCEPROP 1 LAST PACK_TYPE 0402
J 1
(-2825 925);
DISPLAY 0.617021 (-2825 925);
PAINT SKYBLUE (-2825 925);
FORCEPROP 1 LAST LOCATION PC1339
J 1
(-3500 925);
DISPLAY 0.617021 (-3500 925);
PAINT AQUA (-3500 925);
FORCEPROP 1 LASTPIN (-3400 925) $PN 1
J 0
(-3410 940);
DISPLAY 0.617021 (-3410 940);
FORCEPROP 1 LASTPIN (-3200 925) $PN 2
J 0
(-3215 940);
DISPLAY 0.617021 (-3215 940);
FORCEPROP 2 LAST CDS_LIB pure_quanta
J 0
(-3300 925);
PAINT MONO (-3300 925);
DISPLAY INVISIBLE (-3300 925);
FORCEPROP 1 LAST PATH I34
J 0
(-3300 1125);
DISPLAY 0.978723 (-3300 1125);
PAINT WHITE (-3300 1125);
DISPLAY INVISIBLE (-3300 1125);
FORCEPROP 2 LAST $SEC 1
J 0
(-3300 1175);
DISPLAY 0.680851 (-3300 1175);
PAINT MONO (-3300 1175);
DISPLAY INVISIBLE (-3300 1175);
FORCEPROP 2 LAST CDS_SEC 1
J 0
(-3300 1175);
DISPLAY 1.021277 (-3300 1175);
DISPLAY INVISIBLE (-3300 1175);
FORCEADD UNIVERSAL_GND..1
(-3625 1375);
FORCEPROP 3 LASTPIN (-3625 1425) SIG_NAME GND\g
J 0
(-3615 1435);
DISPLAY 0.659574 (-3615 1435);
PAINT MONO (-3615 1435);
DISPLAY INVISIBLE (-3615 1435);
FORCEPROP 1 LAST HDL_POWER GND
J 1
(-3600 1300);
DISPLAY 0.872340 (-3600 1300);
PAINT GREEN (-3600 1300);
DISPLAY INVISIBLE (-3600 1300);
FORCEPROP 2 LAST CDS_LIB logical_power
J 0
(-3625 1375);
PAINT MONO (-3625 1375);
DISPLAY INVISIBLE (-3625 1375);
FORCEPROP 1 LAST PATH I35
J 0
(-3550 1375);
DISPLAY 0.872340 (-3550 1375);
PAINT AQUA (-3550 1375);
DISPLAY INVISIBLE (-3550 1375);
FORCEADD Q_CAP..1
(-3625 1625);
FORCEPROP 1 LAST PART_NUMBER CH5222KEB01
J 0
(-3575 1450);
DISPLAY 0.617021 (-3575 1450);
PAINT BLUE (-3575 1450);
DISPLAY INVISIBLE (-3575 1450);
FORCEPROP 1 LAST PACK_TYPE C0402
J 0
(-3575 1500);
DISPLAY 0.617021 (-3575 1500);
PAINT SKYBLUE (-3575 1500);
FORCEPROP 1 LAST VOLTAGE 10V
J 0
(-3575 1650);
DISPLAY 0.617021 (-3575 1650);
PAINT SKYBLUE (-3575 1650);
FORCEPROP 1 LAST VALUE 2.2UF
J 0
(-3575 1700);
DISPLAY 0.617021 (-3575 1700);
PAINT SKYBLUE (-3575 1700);
FORCEPROP 1 LAST MATERIAL X6S
J 0
(-3575 1550);
DISPLAY 0.617021 (-3575 1550);
PAINT SKYBLUE (-3575 1550);
FORCEPROP 1 LAST TOLERANCE 10%
J 0
(-3575 1600);
DISPLAY 0.617021 (-3575 1600);
PAINT SKYBLUE (-3575 1600);
FORCEPROP 1 LAST LOCATION PC557
J 0
(-3575 1750);
DISPLAY 0.617021 (-3575 1750);
PAINT AQUA (-3575 1750);
FORCEPROP 1 LASTPIN (-3625 1725) $PN 1
J 0
(-3615 1705);
DISPLAY 0.617021 (-3615 1705);
PAINT MONO (-3615 1705);
FORCEPROP 1 LASTPIN (-3625 1525) $PN 2
J 0
(-3615 1505);
DISPLAY 0.617021 (-3615 1505);
PAINT MONO (-3615 1505);
FORCEPROP 2 LAST CDS_LIB pure_quanta
J 0
(-3625 1625);
DISPLAY INVISIBLE (-3625 1625);
FORCEPROP 1 LAST PATH I36
J 0
(-3575 1775);
DISPLAY 0.978723 (-3575 1775);
PAINT WHITE (-3575 1775);
DISPLAY INVISIBLE (-3575 1775);
FORCEPROP 1 LAST LOCATION PC557
J 0
(-3575 1800);
DISPLAY 1.021277 (-3575 1800);
PAINT AQUA (-3575 1800);
DISPLAY INVISIBLE (-3575 1800);
FORCEPROP 0 LAST $SEC 1
J 0
(-3575 1800);
DISPLAY 0.680851 (-3575 1800);
PAINT MONO (-3575 1800);
DISPLAY INVISIBLE (-3575 1800);
FORCEPROP 0 LAST CDS_SEC 1
J 0
(-3575 1800);
DISPLAY 1.021277 (-3575 1800);
DISPLAY INVISIBLE (-3575 1800);
FORCEADD Q_RES..2
(-3625 2125);
FORCEPROP 1 LAST PART_NUMBER CS-2202FB01
J 0
(-3585 2000);
DISPLAY 0.617021 (-3585 2000);
PAINT BLUE (-3585 2000);
DISPLAY INVISIBLE (-3585 2000);
FORCEPROP 1 LAST PACK_TYPE 0402LF
J 0
(-3585 1950);
DISPLAY 0.617021 (-3585 1950);
PAINT SKYBLUE (-3585 1950);
FORCEPROP 1 LAST VALUE 2.2
J 0
(-3580 2200);
DISPLAY 0.617021 (-3580 2200);
PAINT SKYBLUE (-3580 2200);
FORCEPROP 1 LAST TOLERANCE 1%
J 0
(-3580 2150);
DISPLAY 0.617021 (-3580 2150);
PAINT SKYBLUE (-3580 2150);
FORCEPROP 1 LAST MATERIAL CHIP
J 0
(-3585 2050);
DISPLAY 0.617021 (-3585 2050);
PAINT SKYBLUE (-3585 2050);
FORCEPROP 1 LAST WATTAGE 1/16W
J 0
(-3585 2100);
DISPLAY 0.617021 (-3585 2100);
PAINT SKYBLUE (-3585 2100);
FORCEPROP 1 LAST LOCATION PR328
J 0
(-3580 2250);
DISPLAY 0.617021 (-3580 2250);
PAINT AQUA (-3580 2250);
FORCEPROP 1 LASTPIN (-3625 2225) $PN 1
J 0
(-3620 2187);
DISPLAY 0.617021 (-3620 2187);
PAINT MONO (-3620 2187);
FORCEPROP 1 LASTPIN (-3625 2025) $PN 2
J 0
(-3620 2035);
DISPLAY 0.617021 (-3620 2035);
PAINT MONO (-3620 2035);
FORCEPROP 2 LAST CDS_LIB pure_quanta
J 0
(-3625 2125);
DISPLAY INVISIBLE (-3625 2125);
FORCEPROP 1 LAST PATH I37
J 0
(-3575 2300);
DISPLAY 0.978723 (-3575 2300);
PAINT WHITE (-3575 2300);
DISPLAY INVISIBLE (-3575 2300);
FORCEPROP 1 LAST LOCATION PR328
J 0
(-3575 2300);
DISPLAY 1.021277 (-3575 2300);
PAINT AQUA (-3575 2300);
DISPLAY INVISIBLE (-3575 2300);
FORCEPROP 0 LAST $SEC 1
J 0
(-3575 2300);
DISPLAY 0.680851 (-3575 2300);
PAINT MONO (-3575 2300);
DISPLAY INVISIBLE (-3575 2300);
FORCEPROP 0 LAST CDS_SEC 1
J 0
(-3575 2300);
DISPLAY 1.021277 (-3575 2300);
DISPLAY INVISIBLE (-3575 2300);
FORCEADD UNIVERSAL_GND..1
(-3200 1900);
FORCEPROP 3 LASTPIN (-3200 1950) SIG_NAME GND\g
J 0
(-3190 1960);
DISPLAY 0.659574 (-3190 1960);
PAINT MONO (-3190 1960);
DISPLAY INVISIBLE (-3190 1960);
FORCEPROP 1 LAST HDL_POWER GND
J 1
(-3175 1825);
DISPLAY 0.872340 (-3175 1825);
PAINT GREEN (-3175 1825);
DISPLAY INVISIBLE (-3175 1825);
FORCEPROP 2 LAST CDS_LIB logical_power
J 0
(-3200 1900);
PAINT MONO (-3200 1900);
DISPLAY INVISIBLE (-3200 1900);
FORCEPROP 1 LAST PATH I38
J 0
(-3125 1900);
DISPLAY 0.872340 (-3125 1900);
PAINT AQUA (-3125 1900);
DISPLAY INVISIBLE (-3125 1900);
FORCEADD Q_CAP..1
(-3200 2125);
FORCEPROP 1 LAST PART_NUMBER CH5222KEB01
J 0
(-3150 2000);
DISPLAY 0.617021 (-3150 2000);
PAINT BLUE (-3150 2000);
DISPLAY INVISIBLE (-3150 2000);
FORCEPROP 1 LAST PACK_TYPE C0402
J 0
(-3150 1950);
DISPLAY 0.617021 (-3150 1950);
PAINT SKYBLUE (-3150 1950);
FORCEPROP 1 LAST VOLTAGE 10V
J 0
(-3150 2150);
DISPLAY 0.617021 (-3150 2150);
PAINT SKYBLUE (-3150 2150);
FORCEPROP 1 LAST VALUE 2.2UF
J 0
(-3150 2200);
DISPLAY 0.617021 (-3150 2200);
PAINT SKYBLUE (-3150 2200);
FORCEPROP 1 LAST TOLERANCE 10%
J 0
(-3150 2100);
DISPLAY 0.617021 (-3150 2100);
PAINT SKYBLUE (-3150 2100);
FORCEPROP 1 LAST MATERIAL X6S
J 0
(-3150 2050);
DISPLAY 0.617021 (-3150 2050);
PAINT SKYBLUE (-3150 2050);
FORCEPROP 1 LAST LOCATION PC559_P1_1
J 0
(-3150 2250);
DISPLAY 0.617021 (-3150 2250);
PAINT AQUA (-3150 2250);
FORCEPROP 1 LASTPIN (-3200 2225) $PN 1
J 0
(-3190 2205);
DISPLAY 0.617021 (-3190 2205);
PAINT MONO (-3190 2205);
FORCEPROP 1 LASTPIN (-3200 2025) $PN 2
J 0
(-3190 2005);
DISPLAY 0.617021 (-3190 2005);
PAINT MONO (-3190 2005);
FORCEPROP 2 LAST CDS_LIB pure_quanta
J 0
(-3200 2125);
DISPLAY INVISIBLE (-3200 2125);
FORCEPROP 1 LAST PATH I39
J 0
(-3150 2275);
DISPLAY 0.978723 (-3150 2275);
PAINT WHITE (-3150 2275);
DISPLAY INVISIBLE (-3150 2275);
FORCEPROP 1 LAST LOCATION PC559_P1_1
J 0
(-3150 2300);
DISPLAY 1.021277 (-3150 2300);
PAINT AQUA (-3150 2300);
DISPLAY INVISIBLE (-3150 2300);
FORCEPROP 0 LAST $SEC 1
J 0
(-3150 2300);
DISPLAY 0.680851 (-3150 2300);
PAINT MONO (-3150 2300);
DISPLAY INVISIBLE (-3150 2300);
FORCEPROP 0 LAST CDS_SEC 1
J 0
(-3150 2300);
DISPLAY 1.021277 (-3150 2300);
DISPLAY INVISIBLE (-3150 2300);
FORCEADD OFFPAGE..5
(-3575 -2200);
FORCEPROP 2 LAST $XR4 284 
J 0
(-3830 -2092);
DISPLAY 0.638298 (-3830 -2092);
PAINT MONO (-3830 -2092);
FORCEPROP 2 LAST $XR3 288 
J 0
(-3830 -2128);
DISPLAY 0.638298 (-3830 -2128);
PAINT MONO (-3830 -2128);
FORCEPROP 2 LAST $XR2 287 
J 0
(-3830 -2164);
DISPLAY 0.638298 (-3830 -2164);
PAINT MONO (-3830 -2164);
FORCEPROP 2 LAST $XR1 286 
J 0
(-3830 -2236);
DISPLAY 0.638298 (-3830 -2236);
PAINT MONO (-3830 -2236);
FORCEPROP 2 LAST $XR0 285 
J 0
(-3830 -2200);
DISPLAY 0.638298 (-3830 -2200);
PAINT MONO (-3830 -2200);
FORCEPROP 1 LAST COMMENT_BODY TRUE
J 0
(-3475 -2275);
DISPLAY 0.872340 (-3475 -2275);
PAINT GREEN (-3475 -2275);
DISPLAY INVISIBLE (-3475 -2275);
FORCEPROP 1 LAST OFFPAGE TRUE
J 0
(-3250 -2325);
DISPLAY 0.872340 (-3250 -2325);
PAINT GREEN (-3250 -2325);
DISPLAY INVISIBLE (-3250 -2325);
FORCEPROP 2 LAST CDS_LIB standard
J 0
(-3575 -2200);
DISPLAY INVISIBLE (-3575 -2200);
FORCEPROP 2 LAST PATH I4
J 0
(-3825 -2075);
DISPLAY 1.021277 (-3825 -2075);
DISPLAY INVISIBLE (-3825 -2075);
FORCEADD ISL99390FRZTR5935..1
(-2100 1125);
FORCEPROP 1 LAST PART_NUMBER AL099390004
J 0
(-2400 1925);
DISPLAY 0.617021 (-2400 1925);
PAINT BLUE (-2400 1925);
DISPLAY INVISIBLE (-2400 1925);
FORCEPROP 2 LAST VALUE ISL99390FRZ-TR5935
J 0
(-2400 2075);
DISPLAY 0.617021 (-2400 2075);
PAINT SKYBLUE (-2400 2075);
FORCEPROP 1 LAST MATERIAL IC
J 0
(-2400 1850);
DISPLAY 0.617021 (-2400 1850);
PAINT SKYBLUE (-2400 1850);
FORCEPROP 2 LAST PART_TYPE SMLF
J 0
(-2400 2125);
DISPLAY 0.638298 (-2400 2125);
FORCEPROP 1 LAST LOCATION PU31_P1_1
J 0
(-2400 2000);
DISPLAY 0.617021 (-2400 2000);
PAINT AQUA (-2400 2000);
FORCEPROP 2 LASTPIN (-1700 675) $PN 2
J 0
(-1690 685);
DISPLAY 0.617021 (-1690 685);
PAINT MONO (-1690 685);
FORCEPROP 2 LASTPIN (-1700 1475) $PN 33
J 0
(-1690 1485);
DISPLAY 0.617021 (-1690 1485);
PAINT MONO (-1690 1485);
FORCEPROP 2 LASTPIN (-2550 875) $PN 31
J 2
(-2560 885);
DISPLAY 0.617021 (-2560 885);
PAINT MONO (-2560 885);
FORCEPROP 2 LASTPIN (-2550 1275) $PN 35
J 2
(-2560 1285);
DISPLAY 0.617021 (-2560 1285);
PAINT MONO (-2560 1285);
FORCEPROP 2 LASTPIN (-1700 825) $PN 6
J 0
(-1690 835);
DISPLAY 0.617021 (-1690 835);
PAINT MONO (-1690 835);
FORCEPROP 2 LASTPIN (-1700 775) $PN 41
J 0
(-1690 785);
DISPLAY 0.617021 (-1690 785);
PAINT MONO (-1690 785);
FORCEPROP 2 LASTPIN (-2550 1125) $PN 38
J 2
(-2560 1135);
DISPLAY 0.617021 (-2560 1135);
PAINT MONO (-2560 1135);
FORCEPROP 2 LASTPIN (-2550 825) $PN 37
J 2
(-2560 835);
DISPLAY 0.617021 (-2560 835);
PAINT MONO (-2560 835);
FORCEPROP 2 LASTPIN (-1700 625) $PN 5
J 0
(-1690 635);
DISPLAY 0.617021 (-1690 635);
PAINT MONO (-1690 635);
FORCEPROP 2 LASTPIN (-1700 575) $PN 7_9-20_24
J 0
(-1690 585);
DISPLAY 0.617021 (-1690 585);
PAINT MONO (-1690 585);
FORCEPROP 2 LASTPIN (-1700 525) $PN 40
J 0
(-1690 535);
DISPLAY 0.617021 (-1690 535);
PAINT MONO (-1690 535);
FORCEPROP 2 LASTPIN (-1700 1225) $PN 32
J 0
(-1690 1235);
DISPLAY 0.617021 (-1690 1235);
PAINT MONO (-1690 1235);
FORCEPROP 2 LASTPIN (-2550 1775) $PN 4
J 2
(-2560 1785);
DISPLAY 0.617021 (-2560 1785);
PAINT MONO (-2560 1785);
FORCEPROP 2 LASTPIN (-2550 525) $PN 34
J 2
(-2560 535);
DISPLAY 0.617021 (-2560 535);
PAINT MONO (-2560 535);
FORCEPROP 2 LASTPIN (-2550 1025) $PN 39
J 2
(-2560 1035);
DISPLAY 0.617021 (-2560 1035);
PAINT MONO (-2560 1035);
FORCEPROP 2 LASTPIN (-1700 1125) $PN 10_19
J 0
(-1690 1135);
DISPLAY 0.617021 (-1690 1135);
PAINT MONO (-1690 1135);
FORCEPROP 2 LASTPIN (-2550 625) $PN 36
J 2
(-2560 635);
DISPLAY 0.617021 (-2560 635);
PAINT MONO (-2560 635);
FORCEPROP 2 LASTPIN (-2550 1475) $PN 3
J 2
(-2560 1485);
DISPLAY 0.617021 (-2560 1485);
PAINT MONO (-2560 1485);
FORCEPROP 2 LASTPIN (-1700 1775) $PN 25_29
J 0
(-1690 1785);
DISPLAY 0.617021 (-1690 1785);
PAINT MONO (-1690 1785);
FORCEPROP 2 LASTPIN (-1700 1725) $PN 30
J 0
(-1690 1735);
DISPLAY 0.617021 (-1690 1735);
PAINT MONO (-1690 1735);
FORCEPROP 2 LASTPIN (-1700 875) $PN 1
J 0
(-1690 885);
DISPLAY 0.617021 (-1690 885);
PAINT MONO (-1690 885);
FORCEPROP 2 LAST CDS_LIB pure_quanta
J 0
(-2100 1125);
DISPLAY INVISIBLE (-2100 1125);
FORCEPROP 1 LAST CDS_LMAN_SYM_OUTLINE -300,700,250,-650
J 0
(-2100 1125);
DISPLAY 0.468085 (-2100 1125);
PAINT GREEN (-2100 1125);
DISPLAY INVISIBLE (-2100 1125);
FORCEPROP 1 LAST NEEDS_NO_SIZE TRUE
J 0
(-2100 1125);
DISPLAY 0.723404 (-2100 1125);
PAINT GREEN (-2100 1125);
DISPLAY INVISIBLE (-2100 1125);
FORCEPROP 1 LAST PATH I40
J 0
(-2100 1125);
DISPLAY 0.723404 (-2100 1125);
PAINT GREEN (-2100 1125);
DISPLAY INVISIBLE (-2100 1125);
FORCEPROP 2 LAST $SEC 1
J 0
(-2400 2050);
DISPLAY 0.680851 (-2400 2050);
PAINT MONO (-2400 2050);
DISPLAY INVISIBLE (-2400 2050);
FORCEPROP 2 LAST CDS_SEC 1
J 0
(-2400 2050);
DISPLAY 1.021277 (-2400 2050);
DISPLAY INVISIBLE (-2400 2050);
FORCEADD Q_RES..2
(-3475 2800);
FORCEPROP 1 LAST PART_NUMBER CS00002JB13
J 0
(-3435 2675);
DISPLAY 0.617021 (-3435 2675);
PAINT BLUE (-3435 2675);
DISPLAY INVISIBLE (-3435 2675);
FORCEPROP 1 LAST PACK_TYPE 0402LF
J 0
(-3435 2625);
DISPLAY 0.617021 (-3435 2625);
PAINT SKYBLUE (-3435 2625);
FORCEPROP 1 LAST VALUE 0
J 0
(-3430 2875);
DISPLAY 0.617021 (-3430 2875);
PAINT SKYBLUE (-3430 2875);
FORCEPROP 1 LAST TOLERANCE 5%
J 0
(-3430 2825);
DISPLAY 0.617021 (-3430 2825);
PAINT SKYBLUE (-3430 2825);
FORCEPROP 1 LAST MATERIAL EMPTY
J 0
(-3435 2725);
DISPLAY 0.617021 (-3435 2725);
PAINT RED (-3435 2725);
FORCEPROP 1 LAST WATTAGE 1/16W
J 0
(-3435 2775);
DISPLAY 0.617021 (-3435 2775);
PAINT SKYBLUE (-3435 2775);
FORCEPROP 1 LAST LOCATION PR640
J 0
(-3430 2925);
DISPLAY 0.617021 (-3430 2925);
PAINT AQUA (-3430 2925);
FORCEPROP 2 LAST CDS_LIB pure_quanta
J 0
(-3475 2800);
DISPLAY INVISIBLE (-3475 2800);
FORCEPROP 1 LAST PATH I41
J 0
(-3425 2975);
DISPLAY 0.978723 (-3425 2975);
PAINT WHITE (-3425 2975);
DISPLAY INVISIBLE (-3425 2975);
FORCEPROP 0 LAST $SEC 1
J 0
(-3425 2975);
DISPLAY INVISIBLE (-3425 2975);
FORCEPROP 0 LAST CDS_SEC 1
J 0
(-3425 2975);
DISPLAY INVISIBLE (-3425 2975);
FORCEPROP 1 LASTPIN (-3475 2900) $PN 1
J 0
(-3470 2862);
DISPLAY 0.787234 (-3470 2862);
PAINT MONO (-3470 2862);
DISPLAY INVISIBLE (-3470 2862);
FORCEPROP 1 LASTPIN (-3475 2700) $PN 2
J 0
(-3470 2710);
DISPLAY 0.787234 (-3470 2710);
PAINT MONO (-3470 2710);
DISPLAY INVISIBLE (-3470 2710);
FORCEADD VCC15..1
(-3475 3025);
FORCEPROP 3 LASTPIN (-3475 2975) SIG_NAME P3V3\g
J 0
(-3465 2985);
DISPLAY 0.659574 (-3465 2985);
PAINT MONO (-3465 2985);
DISPLAY INVISIBLE (-3465 2985);
FORCEPROP 1 LAST HDL_POWER P3V3
J 1
(-3475 3075);
DISPLAY 0.617021 (-3475 3075);
PAINT GREEN (-3475 3075);
FORCEPROP 2 LAST CDS_LIB logical_power
J 0
(-3475 3025);
DISPLAY INVISIBLE (-3475 3025);
FORCEPROP 1 LAST PATH I42
J 0
(-3425 3050);
DISPLAY 0.872340 (-3425 3050);
PAINT AQUA (-3425 3050);
DISPLAY INVISIBLE (-3425 3050);
FORCEADD UNIVERSAL_GND..1
(-1450 400);
FORCEPROP 3 LASTPIN (-1450 450) SIG_NAME GND\g
J 0
(-1440 460);
DISPLAY 0.659574 (-1440 460);
PAINT MONO (-1440 460);
DISPLAY INVISIBLE (-1440 460);
FORCEPROP 1 LAST HDL_POWER GND
J 1
(-1425 325);
DISPLAY 0.872340 (-1425 325);
PAINT GREEN (-1425 325);
DISPLAY INVISIBLE (-1425 325);
FORCEPROP 2 LAST CDS_LIB logical_power
J 0
(-1450 400);
PAINT MONO (-1450 400);
DISPLAY INVISIBLE (-1450 400);
FORCEPROP 1 LAST PATH I43
J 0
(-1375 400);
DISPLAY 0.872340 (-1375 400);
PAINT AQUA (-1375 400);
DISPLAY INVISIBLE (-1375 400);
FORCEADD Q_CAP..1
(-1300 2025);
FORCEPROP 1 LAST PART_NUMBER TMP_QCH2336K1B12
J 0
(-1250 1875);
DISPLAY 0.617021 (-1250 1875);
PAINT BLUE (-1250 1875);
DISPLAY INVISIBLE (-1250 1875);
FORCEPROP 1 LAST PACK_TYPE 0402
J 0
(-1250 1925);
DISPLAY 0.617021 (-1250 1925);
PAINT SKYBLUE (-1250 1925);
FORCEPROP 1 LAST VOLTAGE 50V
J 0
(-1250 2075);
DISPLAY 0.617021 (-1250 2075);
PAINT SKYBLUE (-1250 2075);
FORCEPROP 1 LAST VALUE 3300PF
J 0
(-1250 2125);
DISPLAY 0.617021 (-1250 2125);
PAINT SKYBLUE (-1250 2125);
FORCEPROP 1 LAST TOLERANCE 10%
J 0
(-1250 2025);
DISPLAY 0.617021 (-1250 2025);
PAINT SKYBLUE (-1250 2025);
FORCEPROP 1 LAST MATERIAL X7R
J 0
(-1250 1975);
DISPLAY 0.617021 (-1250 1975);
PAINT SKYBLUE (-1250 1975);
FORCEPROP 1 LAST LOCATION PC561_P1_1
J 0
(-1250 2175);
DISPLAY 0.617021 (-1250 2175);
PAINT AQUA (-1250 2175);
FORCEPROP 1 LASTPIN (-1300 2125) $PN 1
J 0
(-1290 2105);
DISPLAY 0.617021 (-1290 2105);
PAINT MONO (-1290 2105);
FORCEPROP 1 LASTPIN (-1300 1925) $PN 2
J 0
(-1290 1905);
DISPLAY 0.617021 (-1290 1905);
PAINT MONO (-1290 1905);
FORCEPROP 2 LAST CDS_LIB pure_quanta
J 0
(-1300 2025);
DISPLAY INVISIBLE (-1300 2025);
FORCEPROP 1 LAST PATH I44
J 0
(-1250 2175);
DISPLAY 0.978723 (-1250 2175);
PAINT WHITE (-1250 2175);
DISPLAY INVISIBLE (-1250 2175);
FORCEPROP 1 LAST LOCATION PC561_P1_1
J 0
(-1250 2225);
DISPLAY 1.021277 (-1250 2225);
PAINT AQUA (-1250 2225);
DISPLAY INVISIBLE (-1250 2225);
FORCEPROP 0 LAST $SEC 1
J 0
(-1250 2225);
DISPLAY 0.680851 (-1250 2225);
PAINT MONO (-1250 2225);
DISPLAY INVISIBLE (-1250 2225);
FORCEPROP 0 LAST CDS_SEC 1
J 0
(-1250 2225);
DISPLAY 1.021277 (-1250 2225);
DISPLAY INVISIBLE (-1250 2225);
FORCEADD OFFPAGE..6
(-225 900);
FORCEPROP 2 LAST $XR0 285 
J 0
(-535 900);
DISPLAY 0.638298 (-535 900);
PAINT MONO (-535 900);
FORCEPROP 1 LAST COMMENT_BODY TRUE
J 0
(-125 825);
DISPLAY 0.872340 (-125 825);
PAINT GREEN (-125 825);
DISPLAY INVISIBLE (-125 825);
FORCEPROP 1 LAST OFFPAGE TRUE
J 0
(100 775);
DISPLAY 0.872340 (100 775);
PAINT GREEN (100 775);
DISPLAY INVISIBLE (100 775);
FORCEPROP 2 LAST CDS_LIB standard
J 0
(-225 900);
DISPLAY INVISIBLE (-225 900);
FORCEPROP 2 LAST PATH I45
J 0
(-525 950);
DISPLAY 1.021277 (-525 950);
DISPLAY INVISIBLE (-525 950);
FORCEADD Q_RES..1
(-850 1575);
FORCEPROP 1 LAST PART_NUMBER CS-3302FB01
J 0
(-950 1625);
DISPLAY 0.617021 (-950 1625);
PAINT BLUE (-950 1625);
DISPLAY INVISIBLE (-950 1625);
FORCEPROP 1 LAST TOLERANCE 1%
J 0
(-700 1575);
DISPLAY 0.617021 (-700 1575);
PAINT SKYBLUE (-700 1575);
FORCEPROP 1 LAST MATERIAL CHIP
J 0
(-950 1675);
DISPLAY 0.617021 (-950 1675);
PAINT SKYBLUE (-950 1675);
FORCEPROP 1 LAST WATTAGE 1/16W
J 2
(-550 1650);
DISPLAY 0.617021 (-550 1650);
PAINT SKYBLUE (-550 1650);
FORCEPROP 1 LAST PACK_TYPE 0402LF
J 0
(-950 1650);
DISPLAY 0.617021 (-950 1650);
PAINT SKYBLUE (-950 1650);
FORCEPROP 1 LAST VALUE 3.3
J 2
(-725 1575);
DISPLAY 0.617021 (-725 1575);
PAINT SKYBLUE (-725 1575);
FORCEPROP 1 LAST LOCATION PR1767
J 0
(-1050 1575);
DISPLAY 0.617021 (-1050 1575);
PAINT AQUA (-1050 1575);
FORCEPROP 1 LASTPIN (-950 1575) $PN 1
J 0
(-938 1587);
DISPLAY 0.617021 (-938 1587);
FORCEPROP 1 LASTPIN (-750 1575) $PN 2
J 0
(-788 1587);
DISPLAY 0.617021 (-788 1587);
FORCEPROP 2 LAST CDS_LIB pure_quanta
J 0
(-850 1575);
PAINT MONO (-850 1575);
DISPLAY INVISIBLE (-850 1575);
FORCEPROP 1 LAST PATH I46
J 0
(-900 1725);
DISPLAY 0.978723 (-900 1725);
PAINT WHITE (-900 1725);
DISPLAY INVISIBLE (-900 1725);
FORCEPROP 2 LAST $SEC 1
J 0
(-900 1775);
DISPLAY 0.680851 (-900 1775);
PAINT MONO (-900 1775);
DISPLAY INVISIBLE (-900 1775);
FORCEPROP 2 LAST CDS_SEC 1
J 0
(-900 1775);
DISPLAY 1.021277 (-900 1775);
DISPLAY INVISIBLE (-900 1775);
FORCEADD Q_CAP..1
(-900 2025);
FORCEPROP 1 LAST PART_NUMBER CH5103KEB01
J 0
(-850 1875);
DISPLAY 0.617021 (-850 1875);
PAINT BLUE (-850 1875);
DISPLAY INVISIBLE (-850 1875);
FORCEPROP 1 LAST PACK_TYPE C0402
J 0
(-850 1925);
DISPLAY 0.617021 (-850 1925);
PAINT SKYBLUE (-850 1925);
FORCEPROP 1 LAST VOLTAGE 16V
J 0
(-850 2075);
DISPLAY 0.617021 (-850 2075);
PAINT SKYBLUE (-850 2075);
FORCEPROP 1 LAST VALUE 1UF
J 0
(-850 2125);
DISPLAY 0.617021 (-850 2125);
PAINT SKYBLUE (-850 2125);
FORCEPROP 1 LAST MATERIAL X6S
J 0
(-850 1975);
DISPLAY 0.617021 (-850 1975);
PAINT SKYBLUE (-850 1975);
FORCEPROP 1 LAST TOLERANCE 10%
J 0
(-850 2025);
DISPLAY 0.617021 (-850 2025);
PAINT SKYBLUE (-850 2025);
FORCEPROP 1 LAST LOCATION PC563_P1_1
J 0
(-850 2175);
DISPLAY 0.617021 (-850 2175);
PAINT AQUA (-850 2175);
FORCEPROP 1 LASTPIN (-900 2125) $PN 1
J 0
(-890 2105);
DISPLAY 0.617021 (-890 2105);
PAINT MONO (-890 2105);
FORCEPROP 1 LASTPIN (-900 1925) $PN 2
J 0
(-890 1905);
DISPLAY 0.617021 (-890 1905);
PAINT MONO (-890 1905);
FORCEPROP 2 LAST CDS_LIB pure_quanta
J 0
(-900 2025);
DISPLAY INVISIBLE (-900 2025);
FORCEPROP 1 LAST PATH I47
J 0
(-850 2175);
DISPLAY 0.978723 (-850 2175);
PAINT WHITE (-850 2175);
DISPLAY INVISIBLE (-850 2175);
FORCEPROP 1 LAST LOCATION PC563_P1_1
J 0
(-850 2225);
DISPLAY 1.021277 (-850 2225);
PAINT AQUA (-850 2225);
DISPLAY INVISIBLE (-850 2225);
FORCEPROP 0 LAST $SEC 1
J 0
(-850 2225);
DISPLAY 0.680851 (-850 2225);
PAINT MONO (-850 2225);
DISPLAY INVISIBLE (-850 2225);
FORCEPROP 0 LAST CDS_SEC 1
J 0
(-850 2225);
DISPLAY 1.021277 (-850 2225);
DISPLAY INVISIBLE (-850 2225);
FORCEADD Q_CAP..1
(-500 2025);
FORCEPROP 1 LAST PART_NUMBER CH6223MEA01
J 0
(-450 1875);
DISPLAY 0.617021 (-450 1875);
PAINT BLUE (-450 1875);
DISPLAY INVISIBLE (-450 1875);
FORCEPROP 1 LAST TOLERANCE 20%
J 0
(-450 2025);
DISPLAY 0.617021 (-450 2025);
PAINT SKYBLUE (-450 2025);
FORCEPROP 1 LAST PACK_TYPE C0805
J 0
(-450 1925);
DISPLAY 0.617021 (-450 1925);
PAINT SKYBLUE (-450 1925);
FORCEPROP 1 LAST VOLTAGE 16V
J 0
(-450 2075);
DISPLAY 0.617021 (-450 2075);
PAINT SKYBLUE (-450 2075);
FORCEPROP 1 LAST VALUE 22UF
J 0
(-450 2125);
DISPLAY 0.617021 (-450 2125);
PAINT SKYBLUE (-450 2125);
FORCEPROP 1 LAST MATERIAL X6S
J 0
(-450 1975);
DISPLAY 0.617021 (-450 1975);
PAINT SKYBLUE (-450 1975);
FORCEPROP 1 LAST LOCATION PC567_P1_1
J 0
(-450 2175);
DISPLAY 0.617021 (-450 2175);
PAINT AQUA (-450 2175);
FORCEPROP 1 LASTPIN (-500 2125) $PN 1
J 0
(-490 2105);
DISPLAY 0.617021 (-490 2105);
PAINT MONO (-490 2105);
FORCEPROP 1 LASTPIN (-500 1925) $PN 2
J 0
(-490 1905);
DISPLAY 0.617021 (-490 1905);
PAINT MONO (-490 1905);
FORCEPROP 2 LAST CDS_LIB pure_quanta
J 0
(-500 2025);
DISPLAY INVISIBLE (-500 2025);
FORCEPROP 1 LAST PATH I48
J 0
(-450 2175);
DISPLAY 0.978723 (-450 2175);
PAINT WHITE (-450 2175);
DISPLAY INVISIBLE (-450 2175);
FORCEPROP 1 LAST LOCATION PC567_P1_1
J 0
(-450 2225);
DISPLAY 1.021277 (-450 2225);
PAINT AQUA (-450 2225);
DISPLAY INVISIBLE (-450 2225);
FORCEPROP 0 LAST $SEC 1
J 0
(-450 2225);
DISPLAY 0.680851 (-450 2225);
PAINT MONO (-450 2225);
DISPLAY INVISIBLE (-450 2225);
FORCEPROP 0 LAST CDS_SEC 1
J 0
(-450 2225);
DISPLAY 1.021277 (-450 2225);
DISPLAY INVISIBLE (-450 2225);
FORCEADD Q_CAP..1
R 2
(-125 1400);
FORCEPROP 1 LAST PART_NUMBER CH4106K1B01
J 2
(-175 1325);
DISPLAY 0.617021 (-175 1325);
PAINT BLUE (-175 1325);
DISPLAY INVISIBLE (-175 1325);
FORCEPROP 1 LAST PACK_TYPE C0402
J 2
(-175 1300);
DISPLAY 0.617021 (-175 1300);
PAINT SKYBLUE (-175 1300);
FORCEPROP 1 LAST VOLTAGE 50V
J 2
(-175 1400);
DISPLAY 0.617021 (-175 1400);
PAINT SKYBLUE (-175 1400);
FORCEPROP 1 LAST VALUE 100NF
J 2
(-175 1425);
DISPLAY 0.617021 (-175 1425);
PAINT SKYBLUE (-175 1425);
FORCEPROP 1 LAST TOLERANCE 10%
J 2
(-175 1375);
DISPLAY 0.617021 (-175 1375);
PAINT SKYBLUE (-175 1375);
FORCEPROP 1 LAST MATERIAL X7R
J 2
(-175 1350);
DISPLAY 0.617021 (-175 1350);
PAINT SKYBLUE (-175 1350);
FORCEPROP 1 LAST LOCATION PC565
J 2
(-175 1475);
DISPLAY 0.617021 (-175 1475);
PAINT AQUA (-175 1475);
FORCEPROP 1 LASTPIN (-125 1500) $PN 1
J 2
(-135 1480);
DISPLAY 0.617021 (-135 1480);
FORCEPROP 1 LASTPIN (-125 1300) $PN 2
J 2
(-135 1280);
DISPLAY 0.617021 (-135 1280);
FORCEPROP 2 LAST CDS_LIB pure_quanta
J 2
(-125 1400);
PAINT MONO (-125 1400);
DISPLAY INVISIBLE (-125 1400);
FORCEPROP 1 LAST PATH I49
J 2
(-175 1550);
DISPLAY 0.978723 (-175 1550);
PAINT WHITE (-175 1550);
DISPLAY INVISIBLE (-175 1550);
FORCEPROP 2 LAST $SEC 1
J 0
(-175 1600);
DISPLAY 0.680851 (-175 1600);
PAINT MONO (-175 1600);
DISPLAY INVISIBLE (-175 1600);
FORCEPROP 2 LAST CDS_SEC 1
J 0
(-175 1600);
DISPLAY 1.021277 (-175 1600);
DISPLAY INVISIBLE (-175 1600);
FORCEADD OFFPAGE..1
(-3575 -2300);
FORCEPROP 2 LAST $XR0 284 
J 0
(-3857 -2300);
DISPLAY 0.638298 (-3857 -2300);
PAINT MONO (-3857 -2300);
FORCEPROP 1 LAST COMMENT_BODY TRUE
J 0
(-3450 -2400);
DISPLAY 0.872340 (-3450 -2400);
PAINT GREEN (-3450 -2400);
DISPLAY INVISIBLE (-3450 -2400);
FORCEPROP 1 LAST OFFPAGE TRUE
J 0
(-3250 -2425);
DISPLAY 0.872340 (-3250 -2425);
PAINT GREEN (-3250 -2425);
DISPLAY INVISIBLE (-3250 -2425);
FORCEPROP 2 LAST CDS_LIB standard
J 0
(-3575 -2300);
DISPLAY INVISIBLE (-3575 -2300);
FORCEPROP 2 LAST PATH I5
J 0
(-4000 -2250);
DISPLAY 1.021277 (-4000 -2250);
DISPLAY INVISIBLE (-4000 -2250);
FORCEADD Q_CAP..1
(-100 2025);
FORCEPROP 1 LAST PART_NUMBER CH6223MEA01
J 0
(-50 1875);
DISPLAY 0.617021 (-50 1875);
PAINT BLUE (-50 1875);
DISPLAY INVISIBLE (-50 1875);
FORCEPROP 1 LAST TOLERANCE 20%
J 0
(-50 2025);
DISPLAY 0.617021 (-50 2025);
PAINT SKYBLUE (-50 2025);
FORCEPROP 1 LAST PACK_TYPE C0805
J 0
(-50 1925);
DISPLAY 0.617021 (-50 1925);
PAINT SKYBLUE (-50 1925);
FORCEPROP 1 LAST VOLTAGE 16V
J 0
(-50 2075);
DISPLAY 0.617021 (-50 2075);
PAINT SKYBLUE (-50 2075);
FORCEPROP 1 LAST VALUE 22UF
J 0
(-50 2125);
DISPLAY 0.617021 (-50 2125);
PAINT SKYBLUE (-50 2125);
FORCEPROP 1 LAST MATERIAL X6S
J 0
(-50 1975);
DISPLAY 0.617021 (-50 1975);
PAINT SKYBLUE (-50 1975);
FORCEPROP 1 LAST LOCATION PC569_P1_1
J 0
(-50 2175);
DISPLAY 0.617021 (-50 2175);
PAINT AQUA (-50 2175);
FORCEPROP 1 LASTPIN (-100 2125) $PN 1
J 0
(-90 2105);
DISPLAY 0.617021 (-90 2105);
PAINT MONO (-90 2105);
FORCEPROP 1 LASTPIN (-100 1925) $PN 2
J 0
(-90 1905);
DISPLAY 0.617021 (-90 1905);
PAINT MONO (-90 1905);
FORCEPROP 2 LAST CDS_LIB pure_quanta
J 0
(-100 2025);
DISPLAY INVISIBLE (-100 2025);
FORCEPROP 1 LAST PATH I50
J 0
(-50 2175);
DISPLAY 0.978723 (-50 2175);
PAINT WHITE (-50 2175);
DISPLAY INVISIBLE (-50 2175);
FORCEPROP 1 LAST LOCATION PC569_P1_1
J 0
(-50 2225);
DISPLAY 1.021277 (-50 2225);
PAINT AQUA (-50 2225);
DISPLAY INVISIBLE (-50 2225);
FORCEPROP 0 LAST $SEC 1
J 0
(-50 2225);
DISPLAY 0.680851 (-50 2225);
PAINT MONO (-50 2225);
DISPLAY INVISIBLE (-50 2225);
FORCEPROP 0 LAST CDS_SEC 1
J 0
(-50 2225);
DISPLAY 1.021277 (-50 2225);
DISPLAY INVISIBLE (-50 2225);
FORCEADD Q_RES..1
(375 -2250);
FORCEPROP 1 LAST PART_NUMBER CS00002JB13
J 0
(250 -2200);
DISPLAY 0.617021 (250 -2200);
PAINT BLUE (250 -2200);
DISPLAY INVISIBLE (250 -2200);
FORCEPROP 1 LAST PACK_TYPE 0402LF
J 0
(250 -2150);
DISPLAY 0.617021 (250 -2150);
PAINT SKYBLUE (250 -2150);
FORCEPROP 1 LAST VALUE 0
J 2
(550 -2250);
DISPLAY 0.617021 (550 -2250);
PAINT SKYBLUE (550 -2250);
FORCEPROP 1 LAST TOLERANCE 5%
J 0
(575 -2250);
DISPLAY 0.617021 (575 -2250);
PAINT SKYBLUE (575 -2250);
FORCEPROP 1 LAST MATERIAL CHIP
J 0
(650 -2250);
DISPLAY 0.617021 (650 -2250);
PAINT SKYBLUE (650 -2250);
FORCEPROP 1 LAST WATTAGE 1/16W
J 2
(625 -2150);
DISPLAY 0.617021 (625 -2150);
PAINT SKYBLUE (625 -2150);
FORCEPROP 1 LAST LOCATION PR329
J 0
(100 -2250);
DISPLAY 0.617021 (100 -2250);
PAINT AQUA (100 -2250);
FORCEPROP 1 LASTPIN (275 -2250) $PN 1
J 0
(287 -2238);
DISPLAY 0.617021 (287 -2238);
PAINT MONO (287 -2238);
FORCEPROP 1 LASTPIN (475 -2250) $PN 2
J 0
(437 -2238);
DISPLAY 0.617021 (437 -2238);
PAINT MONO (437 -2238);
FORCEPROP 2 LAST CDS_LIB pure_quanta
J 0
(375 -2250);
DISPLAY INVISIBLE (375 -2250);
FORCEPROP 1 LAST PATH I51
J 0
(325 -2100);
DISPLAY 0.978723 (325 -2100);
PAINT WHITE (325 -2100);
DISPLAY INVISIBLE (325 -2100);
FORCEPROP 0 LAST $SEC 1
J 0
(625 -2100);
DISPLAY 0.680851 (625 -2100);
PAINT MONO (625 -2100);
DISPLAY INVISIBLE (625 -2100);
FORCEPROP 0 LAST CDS_SEC 1
J 0
(625 -2100);
DISPLAY 1.021277 (625 -2100);
DISPLAY INVISIBLE (625 -2100);
FORCEADD OFFPAGE..3
(1500 -1950);
FORCEPROP 2 LAST $XR0 285 
J 0
(1714 -1950);
DISPLAY 0.638298 (1714 -1950);
PAINT MONO (1714 -1950);
FORCEPROP 1 LAST COMMENT_BODY TRUE
J 0
(1450 -2050);
DISPLAY 0.872340 (1450 -2050);
PAINT GREEN (1450 -2050);
DISPLAY INVISIBLE (1450 -2050);
FORCEPROP 1 LAST OFFPAGE TRUE
J 0
(1825 -2075);
DISPLAY 0.872340 (1825 -2075);
PAINT GREEN (1825 -2075);
DISPLAY INVISIBLE (1825 -2075);
FORCEPROP 2 LAST CDS_LIB standard
J 0
(1500 -1950);
DISPLAY INVISIBLE (1500 -1950);
FORCEPROP 2 LAST PATH I52
J 0
(1725 -1900);
DISPLAY 1.021277 (1725 -1900);
DISPLAY INVISIBLE (1725 -1900);
FORCEADD Q_CAP..1
(250 -800);
FORCEPROP 1 LAST PART_NUMBER CH6223MEA01
J 0
(300 -950);
DISPLAY 0.617021 (300 -950);
PAINT BLUE (300 -950);
DISPLAY INVISIBLE (300 -950);
FORCEPROP 1 LAST TOLERANCE 20%
J 0
(300 -800);
DISPLAY 0.617021 (300 -800);
PAINT SKYBLUE (300 -800);
FORCEPROP 1 LAST PACK_TYPE C0805
J 0
(300 -900);
DISPLAY 0.617021 (300 -900);
PAINT SKYBLUE (300 -900);
FORCEPROP 1 LAST VOLTAGE 16V
J 0
(300 -750);
DISPLAY 0.617021 (300 -750);
PAINT SKYBLUE (300 -750);
FORCEPROP 1 LAST VALUE 22UF
J 0
(300 -700);
DISPLAY 0.617021 (300 -700);
PAINT SKYBLUE (300 -700);
FORCEPROP 1 LAST MATERIAL X6S
J 0
(300 -850);
DISPLAY 0.617021 (300 -850);
PAINT SKYBLUE (300 -850);
FORCEPROP 1 LAST LOCATION PC570_P1_2
J 0
(300 -650);
DISPLAY 0.617021 (300 -650);
PAINT AQUA (300 -650);
FORCEPROP 1 LASTPIN (250 -700) $PN 1
J 0
(260 -720);
DISPLAY 0.617021 (260 -720);
PAINT MONO (260 -720);
FORCEPROP 1 LASTPIN (250 -900) $PN 2
J 0
(260 -920);
DISPLAY 0.617021 (260 -920);
PAINT MONO (260 -920);
FORCEPROP 2 LAST CDS_LIB pure_quanta
J 0
(250 -800);
DISPLAY INVISIBLE (250 -800);
FORCEPROP 1 LAST PATH I53
J 0
(300 -650);
DISPLAY 0.978723 (300 -650);
PAINT WHITE (300 -650);
DISPLAY INVISIBLE (300 -650);
FORCEPROP 1 LAST LOCATION PC570_P1_2
J 0
(300 -600);
DISPLAY 1.021277 (300 -600);
PAINT AQUA (300 -600);
DISPLAY INVISIBLE (300 -600);
FORCEPROP 0 LAST $SEC 1
J 0
(300 -600);
DISPLAY 0.680851 (300 -600);
PAINT MONO (300 -600);
DISPLAY INVISIBLE (300 -600);
FORCEPROP 0 LAST CDS_SEC 1
J 0
(300 -600);
DISPLAY 1.021277 (300 -600);
DISPLAY INVISIBLE (300 -600);
FORCEADD UNIVERSAL_GND..1
(475 -1225);
FORCEPROP 3 LASTPIN (475 -1175) SIG_NAME GND\g
J 0
(485 -1165);
DISPLAY 0.659574 (485 -1165);
PAINT MONO (485 -1165);
DISPLAY INVISIBLE (485 -1165);
FORCEPROP 1 LAST HDL_POWER GND
J 1
(500 -1300);
DISPLAY 0.872340 (500 -1300);
PAINT GREEN (500 -1300);
DISPLAY INVISIBLE (500 -1300);
FORCEPROP 2 LAST CDS_LIB logical_power
J 0
(475 -1225);
PAINT MONO (475 -1225);
DISPLAY INVISIBLE (475 -1225);
FORCEPROP 1 LAST PATH I54
J 0
(550 -1225);
DISPLAY 0.872340 (550 -1225);
PAINT AQUA (550 -1225);
DISPLAY INVISIBLE (550 -1225);
FORCEADD VCC15..1
(475 -425);
FORCEPROP 3 LASTPIN (475 -475) SIG_NAME SW_P12V_PVCCIN_CPU1_FLT\g
J 0
(485 -465);
DISPLAY 0.659574 (485 -465);
PAINT MONO (485 -465);
DISPLAY INVISIBLE (485 -465);
FORCEPROP 1 LAST HDL_POWER SW_P12V_PVCCIN_CPU1_FLT
J 1
(525 -375);
DISPLAY 0.617021 (525 -375);
PAINT GREEN (525 -375);
FORCEPROP 2 LAST CDS_LIB logical_power
J 0
(475 -425);
DISPLAY INVISIBLE (475 -425);
FORCEPROP 1 LAST PATH I55
J 0
(525 -400);
DISPLAY 0.872340 (525 -400);
PAINT AQUA (525 -400);
DISPLAY INVISIBLE (525 -400);
FORCEADD Q_CAPP..1
(2025 -50);
FORCEPROP 1 LAST PART_NUMBER CC7560JMD16
J 0
(2075 -250);
DISPLAY 0.617021 (2075 -250);
PAINT BLUE (2075 -250);
DISPLAY INVISIBLE (2075 -250);
FORCEPROP 1 LAST PACK_TYPE THLF
J 0
(2075 -200);
DISPLAY 0.617021 (2075 -200);
PAINT SKYBLUE (2075 -200);
FORCEPROP 1 LAST VALUE 560UF
J 0
(2075 0);
DISPLAY 0.617021 (2075 0);
PAINT SKYBLUE (2075 0);
FORCEPROP 1 LAST TOLERANCE 20%
J 0
(2075 -50);
DISPLAY 0.617021 (2075 -50);
PAINT SKYBLUE (2075 -50);
FORCEPROP 1 LAST MATERIAL OSCON
J 0
(2075 -150);
DISPLAY 0.617021 (2075 -150);
PAINT SKYBLUE (2075 -150);
FORCEPROP 1 LAST VOLTAGE 2.5V
J 0
(2075 -100);
DISPLAY 0.617021 (2075 -100);
PAINT SKYBLUE (2075 -100);
FORCEPROP 1 LAST LOCATION PC83
J 0
(2075 50);
DISPLAY 0.617021 (2075 50);
PAINT AQUA (2075 50);
FORCEPROP 1 LASTPIN (2025 50) $PN 1
J 0
(2035 35);
DISPLAY 0.617021 (2035 35);
PAINT MONO (2035 35);
FORCEPROP 1 LASTPIN (2025 -150) $PN 2
J 0
(2035 -165);
DISPLAY 0.617021 (2035 -165);
PAINT MONO (2035 -165);
FORCEPROP 2 LAST CDS_LIB pure_quanta
J 0
(2025 -50);
DISPLAY INVISIBLE (2025 -50);
FORCEPROP 1 LAST PATH I56
J 0
(2075 100);
DISPLAY 0.978723 (2075 100);
DISPLAY INVISIBLE (2075 100);
FORCEPROP 0 LAST $SEC 1
J 0
(2075 100);
DISPLAY 0.680851 (2075 100);
PAINT MONO (2075 100);
DISPLAY INVISIBLE (2075 100);
FORCEPROP 0 LAST CDS_SEC 1
J 0
(2075 100);
DISPLAY 1.021277 (2075 100);
DISPLAY INVISIBLE (2075 100);
FORCEADD Q_CAP..1
(2775 -1975);
FORCEPROP 1 LAST PART_NUMBER CH622KMEA03
J 0
(2825 -2150);
DISPLAY 0.617021 (2825 -2150);
PAINT BLUE (2825 -2150);
DISPLAY INVISIBLE (2825 -2150);
FORCEPROP 1 LAST TOLERANCE 20%
J 0
(2825 -2000);
DISPLAY 0.617021 (2825 -2000);
PAINT SKYBLUE (2825 -2000);
FORCEPROP 1 LAST VOLTAGE 4V
J 0
(2825 -1950);
DISPLAY 0.617021 (2825 -1950);
PAINT SKYBLUE (2825 -1950);
FORCEPROP 1 LAST VALUE 22UF
J 0
(2825 -1900);
DISPLAY 0.617021 (2825 -1900);
PAINT SKYBLUE (2825 -1900);
FORCEPROP 1 LAST MATERIAL X6S
J 0
(2825 -2050);
DISPLAY 0.617021 (2825 -2050);
PAINT SKYBLUE (2825 -2050);
FORCEPROP 1 LAST PACK_TYPE C0805
J 0
(2825 -2100);
DISPLAY 0.617021 (2825 -2100);
PAINT SKYBLUE (2825 -2100);
FORCEPROP 1 LAST LOCATION PC575_P1_2
J 0
(2825 -1850);
DISPLAY 0.617021 (2825 -1850);
PAINT AQUA (2825 -1850);
FORCEPROP 1 LASTPIN (2775 -1875) $PN 1
J 0
(2785 -1895);
DISPLAY 0.617021 (2785 -1895);
PAINT MONO (2785 -1895);
FORCEPROP 1 LASTPIN (2775 -2075) $PN 2
J 0
(2785 -2095);
DISPLAY 0.617021 (2785 -2095);
PAINT MONO (2785 -2095);
FORCEPROP 2 LAST CDS_LIB pure_quanta
J 0
(2775 -1975);
DISPLAY INVISIBLE (2775 -1975);
FORCEPROP 1 LAST PATH I57
J 0
(2825 -1825);
DISPLAY 0.978723 (2825 -1825);
PAINT WHITE (2825 -1825);
DISPLAY INVISIBLE (2825 -1825);
FORCEPROP 1 LAST LOCATION PC575_P1_2
J 0
(2825 -1800);
DISPLAY 1.021277 (2825 -1800);
PAINT AQUA (2825 -1800);
DISPLAY INVISIBLE (2825 -1800);
FORCEPROP 0 LAST $SEC 1
J 0
(2825 -1800);
DISPLAY 0.680851 (2825 -1800);
PAINT MONO (2825 -1800);
DISPLAY INVISIBLE (2825 -1800);
FORCEPROP 0 LAST CDS_SEC 1
J 0
(2825 -1800);
DISPLAY 1.021277 (2825 -1800);
DISPLAY INVISIBLE (2825 -1800);
FORCEADD Q_CAP..1
(3200 -1975);
FORCEPROP 1 LAST PART_NUMBER CH622KMEA03
J 0
(3250 -2150);
DISPLAY 0.617021 (3250 -2150);
PAINT BLUE (3250 -2150);
DISPLAY INVISIBLE (3250 -2150);
FORCEPROP 1 LAST TOLERANCE 20%
J 0
(3250 -2000);
DISPLAY 0.617021 (3250 -2000);
PAINT SKYBLUE (3250 -2000);
FORCEPROP 1 LAST VALUE 22UF
J 0
(3250 -1900);
DISPLAY 0.617021 (3250 -1900);
PAINT SKYBLUE (3250 -1900);
FORCEPROP 1 LAST PACK_TYPE C0805
J 0
(3250 -2100);
DISPLAY 0.617021 (3250 -2100);
PAINT SKYBLUE (3250 -2100);
FORCEPROP 1 LAST VOLTAGE 4V
J 0
(3250 -1950);
DISPLAY 0.617021 (3250 -1950);
PAINT SKYBLUE (3250 -1950);
FORCEPROP 1 LAST MATERIAL X6S
J 0
(3250 -2050);
DISPLAY 0.617021 (3250 -2050);
PAINT SKYBLUE (3250 -2050);
FORCEPROP 1 LAST LOCATION PC577_P1_2
J 0
(3250 -1850);
DISPLAY 0.617021 (3250 -1850);
PAINT AQUA (3250 -1850);
FORCEPROP 1 LASTPIN (3200 -1875) $PN 1
J 0
(3210 -1895);
DISPLAY 0.617021 (3210 -1895);
PAINT MONO (3210 -1895);
FORCEPROP 1 LASTPIN (3200 -2075) $PN 2
J 0
(3210 -2095);
DISPLAY 0.617021 (3210 -2095);
PAINT MONO (3210 -2095);
FORCEPROP 2 LAST CDS_LIB pure_quanta
J 0
(3200 -1975);
DISPLAY INVISIBLE (3200 -1975);
FORCEPROP 1 LAST PATH I58
J 0
(3250 -1825);
DISPLAY 0.978723 (3250 -1825);
PAINT WHITE (3250 -1825);
DISPLAY INVISIBLE (3250 -1825);
FORCEPROP 1 LAST LOCATION PC577_P1_2
J 0
(3250 -1800);
DISPLAY 1.021277 (3250 -1800);
PAINT AQUA (3250 -1800);
DISPLAY INVISIBLE (3250 -1800);
FORCEPROP 0 LAST $SEC 1
J 0
(3250 -1800);
DISPLAY 0.680851 (3250 -1800);
PAINT MONO (3250 -1800);
DISPLAY INVISIBLE (3250 -1800);
FORCEPROP 0 LAST CDS_SEC 1
J 0
(3250 -1800);
DISPLAY 1.021277 (3250 -1800);
DISPLAY INVISIBLE (3250 -1800);
FORCEADD Q_RES..2
(3700 -1975);
FORCEPROP 1 LAST PART_NUMBER CS14992FB06
J 0
(3740 -2100);
DISPLAY 0.617021 (3740 -2100);
PAINT BLUE (3740 -2100);
DISPLAY INVISIBLE (3740 -2100);
FORCEPROP 1 LAST PACK_TYPE 0402LF
J 0
(3740 -2150);
DISPLAY 0.617021 (3740 -2150);
PAINT SKYBLUE (3740 -2150);
FORCEPROP 1 LAST MATERIAL CHIP
J 0
(3740 -2050);
DISPLAY 0.617021 (3740 -2050);
PAINT SKYBLUE (3740 -2050);
FORCEPROP 1 LAST WATTAGE 1/16W
J 0
(3740 -2000);
DISPLAY 0.617021 (3740 -2000);
PAINT SKYBLUE (3740 -2000);
FORCEPROP 1 LAST VALUE 499
J 0
(3745 -1900);
DISPLAY 0.617021 (3745 -1900);
PAINT SKYBLUE (3745 -1900);
FORCEPROP 1 LAST TOLERANCE 1%
J 0
(3745 -1950);
DISPLAY 0.617021 (3745 -1950);
PAINT SKYBLUE (3745 -1950);
FORCEPROP 1 LAST LOCATION PR4240
J 0
(3745 -1850);
DISPLAY 0.617021 (3745 -1850);
PAINT AQUA (3745 -1850);
FORCEPROP 1 LASTPIN (3700 -1875) $PN 1
J 0
(3705 -1913);
DISPLAY 0.787234 (3705 -1913);
PAINT MONO (3705 -1913);
FORCEPROP 1 LASTPIN (3700 -2075) $PN 2
J 0
(3705 -2065);
DISPLAY 0.787234 (3705 -2065);
PAINT MONO (3705 -2065);
FORCEPROP 2 LAST CDS_LIB pure_quanta
J 0
(3700 -1975);
DISPLAY INVISIBLE (3700 -1975);
FORCEPROP 2 LAST BOM_COST VR_PCH
J 0
(3750 -1800);
DISPLAY 0.680851 (3750 -1800);
DISPLAY INVISIBLE (3750 -1800);
FORCEPROP 1 LAST PATH I59
J 0
(3750 -1800);
DISPLAY 0.978723 (3750 -1800);
PAINT WHITE (3750 -1800);
DISPLAY INVISIBLE (3750 -1800);
FORCEPROP 0 LAST $SEC 1
J 0
(3750 -1800);
DISPLAY 0.680851 (3750 -1800);
PAINT MONO (3750 -1800);
DISPLAY INVISIBLE (3750 -1800);
FORCEPROP 0 LAST CDS_SEC 1
J 0
(3750 -1800);
DISPLAY 1.021277 (3750 -1800);
DISPLAY INVISIBLE (3750 -1800);
FORCEADD Q_CAP..2
(-3325 -1900);
FORCEPROP 1 LAST PART_NUMBER CH4104K1B00
J 1
(-3100 -1850);
DISPLAY 0.617021 (-3100 -1850);
PAINT BLUE (-3100 -1850);
DISPLAY INVISIBLE (-3100 -1850);
FORCEPROP 1 LAST TOLERANCE 10%
J 2
(-2725 -1850);
DISPLAY 0.617021 (-2725 -1850);
PAINT SKYBLUE (-2725 -1850);
FORCEPROP 1 LAST MATERIAL X7R
J 0
(-2925 -1850);
DISPLAY 0.617021 (-2925 -1850);
PAINT SKYBLUE (-2925 -1850);
FORCEPROP 1 LAST VALUE 0.1UF
J 2
(-3075 -1900);
DISPLAY 0.617021 (-3075 -1900);
PAINT SKYBLUE (-3075 -1900);
FORCEPROP 1 LAST VOLTAGE 25V
J 0
(-3025 -1900);
DISPLAY 0.617021 (-3025 -1900);
PAINT SKYBLUE (-3025 -1900);
FORCEPROP 1 LAST PACK_TYPE 0402
J 1
(-2850 -1900);
DISPLAY 0.617021 (-2850 -1900);
PAINT SKYBLUE (-2850 -1900);
FORCEPROP 1 LAST LOCATION PC1338
J 1
(-3525 -1900);
DISPLAY 0.617021 (-3525 -1900);
PAINT AQUA (-3525 -1900);
FORCEPROP 1 LASTPIN (-3425 -1900) $PN 1
J 0
(-3435 -1885);
DISPLAY 0.617021 (-3435 -1885);
FORCEPROP 1 LASTPIN (-3225 -1900) $PN 2
J 0
(-3240 -1885);
DISPLAY 0.617021 (-3240 -1885);
FORCEPROP 2 LAST CDS_LIB pure_quanta
J 0
(-3325 -1900);
PAINT MONO (-3325 -1900);
DISPLAY INVISIBLE (-3325 -1900);
FORCEPROP 1 LAST PATH I6
J 0
(-3325 -1700);
DISPLAY 0.978723 (-3325 -1700);
PAINT WHITE (-3325 -1700);
DISPLAY INVISIBLE (-3325 -1700);
FORCEPROP 2 LAST $SEC 1
J 0
(-3325 -1650);
DISPLAY 0.680851 (-3325 -1650);
PAINT MONO (-3325 -1650);
DISPLAY INVISIBLE (-3325 -1650);
FORCEPROP 2 LAST CDS_SEC 1
J 0
(-3325 -1650);
DISPLAY 1.021277 (-3325 -1650);
DISPLAY INVISIBLE (-3325 -1650);
FORCEADD UNIVERSAL_GND..1
(4075 -2375);
FORCEPROP 3 LASTPIN (4075 -2325) SIG_NAME GND\g
J 0
(4085 -2315);
DISPLAY 0.659574 (4085 -2315);
PAINT MONO (4085 -2315);
DISPLAY INVISIBLE (4085 -2315);
FORCEPROP 1 LAST HDL_POWER GND
J 1
(4100 -2450);
DISPLAY 0.872340 (4100 -2450);
PAINT GREEN (4100 -2450);
DISPLAY INVISIBLE (4100 -2450);
FORCEPROP 2 LAST CDS_LIB logical_power
J 0
(4075 -2375);
PAINT MONO (4075 -2375);
DISPLAY INVISIBLE (4075 -2375);
FORCEPROP 1 LAST PATH I60
J 0
(4150 -2375);
DISPLAY 0.872340 (4150 -2375);
PAINT AQUA (4150 -2375);
DISPLAY INVISIBLE (4150 -2375);
FORCEADD Q_CAPP..1
(2600 -950);
FORCEPROP 1 LAST PART_NUMBER CH733LY8802
J 0
(2650 -1100);
DISPLAY 0.617021 (2650 -1100);
PAINT BLUE (2650 -1100);
DISPLAY INVISIBLE (2650 -1100);
FORCEPROP 1 LAST VALUE 330UF
J 0
(2650 -850);
DISPLAY 0.617021 (2650 -850);
PAINT SKYBLUE (2650 -850);
FORCEPROP 1 LAST MATERIAL EMPTY
J 0
(2650 -1000);
DISPLAY 0.617021 (2650 -1000);
PAINT RED (2650 -1000);
FORCEPROP 1 LAST VOLTAGE 2.5V
J 0
(2650 -950);
DISPLAY 0.617021 (2650 -950);
PAINT SKYBLUE (2650 -950);
FORCEPROP 1 LAST PACK_TYPE SMLF
J 0
(2650 -1050);
DISPLAY 0.617021 (2650 -1050);
PAINT SKYBLUE (2650 -1050);
FORCEPROP 1 LAST TOLERANCE +10/-35%
J 0
(2650 -900);
DISPLAY 0.617021 (2650 -900);
PAINT SKYBLUE (2650 -900);
FORCEPROP 1 LAST LOCATION PC1990
J 0
(2650 -800);
DISPLAY 0.617021 (2650 -800);
PAINT AQUA (2650 -800);
FORCEPROP 1 LASTPIN (2600 -850) $PN 1
J 0
(2610 -865);
DISPLAY 0.617021 (2610 -865);
PAINT MONO (2610 -865);
FORCEPROP 1 LASTPIN (2600 -1050) $PN 2
J 0
(2610 -1065);
DISPLAY 0.617021 (2610 -1065);
PAINT MONO (2610 -1065);
FORCEPROP 2 LAST CDS_LIB pure_quanta
J 0
(2600 -950);
DISPLAY INVISIBLE (2600 -950);
FORCEPROP 1 LAST PATH I61
J 0
(2650 -800);
DISPLAY 0.978723 (2650 -800);
DISPLAY INVISIBLE (2650 -800);
FORCEPROP 0 LAST $SEC 1
J 0
(2650 -750);
DISPLAY 0.680851 (2650 -750);
PAINT MONO (2650 -750);
DISPLAY INVISIBLE (2650 -750);
FORCEPROP 0 LAST CDS_SEC 1
J 0
(2650 -750);
DISPLAY 1.021277 (2650 -750);
DISPLAY INVISIBLE (2650 -750);
FORCEADD Q_CAPP..1
(3100 -925);
FORCEPROP 1 LAST PART_NUMBER CH733LY8802
J 0
(3150 -1100);
DISPLAY 0.617021 (3150 -1100);
PAINT BLUE (3150 -1100);
DISPLAY INVISIBLE (3150 -1100);
FORCEPROP 1 LAST MATERIAL EMPTY
J 0
(3150 -1000);
DISPLAY 0.617021 (3150 -1000);
PAINT RED (3150 -1000);
FORCEPROP 1 LAST VOLTAGE 2.5V
J 0
(3150 -950);
DISPLAY 0.617021 (3150 -950);
PAINT SKYBLUE (3150 -950);
FORCEPROP 1 LAST TOLERANCE +10/-35%
J 0
(3150 -900);
DISPLAY 0.617021 (3150 -900);
PAINT SKYBLUE (3150 -900);
FORCEPROP 1 LAST VALUE 330UF
J 0
(3150 -850);
DISPLAY 0.617021 (3150 -850);
PAINT SKYBLUE (3150 -850);
FORCEPROP 1 LAST PACK_TYPE SMLF
J 0
(3150 -1050);
DISPLAY 0.617021 (3150 -1050);
PAINT SKYBLUE (3150 -1050);
FORCEPROP 1 LAST LOCATION PC189
J 0
(3150 -800);
DISPLAY 0.617021 (3150 -800);
PAINT AQUA (3150 -800);
FORCEPROP 1 LASTPIN (3100 -825) $PN 1
J 0
(3110 -840);
DISPLAY 0.617021 (3110 -840);
FORCEPROP 1 LASTPIN (3100 -1025) $PN 2
J 0
(3110 -1040);
DISPLAY 0.617021 (3110 -1040);
FORCEPROP 2 LAST CDS_LIB pure_quanta
J 0
(3100 -925);
PAINT MONO (3100 -925);
DISPLAY INVISIBLE (3100 -925);
FORCEPROP 1 LAST PATH I62
J 0
(3150 -775);
DISPLAY 0.978723 (3150 -775);
DISPLAY INVISIBLE (3150 -775);
FORCEPROP 2 LAST $SEC 1
J 0
(3150 -725);
DISPLAY 0.680851 (3150 -725);
PAINT MONO (3150 -725);
DISPLAY INVISIBLE (3150 -725);
FORCEPROP 2 LAST CDS_SEC 1
J 0
(3150 -725);
DISPLAY 1.021277 (3150 -725);
DISPLAY INVISIBLE (3150 -725);
FORCEADD Q_CAPP..1
(2500 -75);
FORCEPROP 1 LAST PART_NUMBER CC7560JMD16
J 0
(2550 -225);
DISPLAY 0.617021 (2550 -225);
PAINT BLUE (2550 -225);
DISPLAY INVISIBLE (2550 -225);
FORCEPROP 1 LAST PACK_TYPE THLF
J 0
(2550 -175);
DISPLAY 0.617021 (2550 -175);
PAINT SKYBLUE (2550 -175);
FORCEPROP 1 LAST VALUE 560UF
J 0
(2550 25);
DISPLAY 0.617021 (2550 25);
PAINT SKYBLUE (2550 25);
FORCEPROP 1 LAST TOLERANCE 20%
J 0
(2550 -25);
DISPLAY 0.617021 (2550 -25);
PAINT SKYBLUE (2550 -25);
FORCEPROP 1 LAST MATERIAL OSCON
J 0
(2550 -125);
DISPLAY 0.617021 (2550 -125);
PAINT SKYBLUE (2550 -125);
FORCEPROP 1 LAST VOLTAGE 2.5V
J 0
(2550 -75);
DISPLAY 0.617021 (2550 -75);
PAINT SKYBLUE (2550 -75);
FORCEPROP 1 LAST LOCATION PC580
J 0
(2550 75);
DISPLAY 0.617021 (2550 75);
PAINT AQUA (2550 75);
FORCEPROP 1 LASTPIN (2500 25) $PN 1
J 0
(2510 10);
DISPLAY 0.617021 (2510 10);
PAINT MONO (2510 10);
FORCEPROP 1 LASTPIN (2500 -175) $PN 2
J 0
(2510 -190);
DISPLAY 0.617021 (2510 -190);
PAINT MONO (2510 -190);
FORCEPROP 2 LAST CDS_LIB pure_quanta
J 0
(2500 -75);
DISPLAY INVISIBLE (2500 -75);
FORCEPROP 1 LAST PATH I63
J 0
(2550 75);
DISPLAY 0.978723 (2550 75);
DISPLAY INVISIBLE (2550 75);
FORCEPROP 1 LAST LOCATION PC580
J 0
(2550 125);
DISPLAY 1.021277 (2550 125);
PAINT AQUA (2550 125);
DISPLAY INVISIBLE (2550 125);
FORCEPROP 0 LAST $SEC 1
J 0
(2550 125);
DISPLAY 0.680851 (2550 125);
PAINT MONO (2550 125);
DISPLAY INVISIBLE (2550 125);
FORCEPROP 0 LAST CDS_SEC 1
J 0
(2550 125);
DISPLAY 1.021277 (2550 125);
DISPLAY INVISIBLE (2550 125);
FORCEADD Q_CAPP..1
(3025 -75);
FORCEPROP 1 LAST PART_NUMBER CC7560JMD16
J 0
(3075 -225);
DISPLAY 0.617021 (3075 -225);
PAINT BLUE (3075 -225);
DISPLAY INVISIBLE (3075 -225);
FORCEPROP 1 LAST PACK_TYPE THLF
J 0
(3075 -175);
DISPLAY 0.617021 (3075 -175);
PAINT SKYBLUE (3075 -175);
FORCEPROP 1 LAST VALUE 560UF
J 0
(3075 25);
DISPLAY 0.617021 (3075 25);
PAINT SKYBLUE (3075 25);
FORCEPROP 1 LAST TOLERANCE 20%
J 0
(3075 -25);
DISPLAY 0.617021 (3075 -25);
PAINT SKYBLUE (3075 -25);
FORCEPROP 1 LAST MATERIAL OSCON
J 0
(3075 -125);
DISPLAY 0.617021 (3075 -125);
PAINT SKYBLUE (3075 -125);
FORCEPROP 1 LAST VOLTAGE 2.5V
J 0
(3075 -75);
DISPLAY 0.617021 (3075 -75);
PAINT SKYBLUE (3075 -75);
FORCEPROP 1 LAST LOCATION PC583
J 0
(3075 75);
DISPLAY 0.617021 (3075 75);
PAINT AQUA (3075 75);
FORCEPROP 1 LASTPIN (3025 25) $PN 1
J 0
(3035 10);
DISPLAY 0.617021 (3035 10);
PAINT MONO (3035 10);
FORCEPROP 1 LASTPIN (3025 -175) $PN 2
J 0
(3035 -190);
DISPLAY 0.617021 (3035 -190);
PAINT MONO (3035 -190);
FORCEPROP 2 LAST CDS_LIB pure_quanta
J 0
(3025 -75);
DISPLAY INVISIBLE (3025 -75);
FORCEPROP 1 LAST PATH I64
J 0
(3075 75);
DISPLAY 0.978723 (3075 75);
DISPLAY INVISIBLE (3075 75);
FORCEPROP 1 LAST LOCATION PC583
J 0
(3075 125);
DISPLAY 1.021277 (3075 125);
PAINT AQUA (3075 125);
DISPLAY INVISIBLE (3075 125);
FORCEPROP 0 LAST $SEC 1
J 0
(3075 125);
DISPLAY 0.680851 (3075 125);
PAINT MONO (3075 125);
DISPLAY INVISIBLE (3075 125);
FORCEPROP 0 LAST CDS_SEC 1
J 0
(3075 125);
DISPLAY 1.021277 (3075 125);
DISPLAY INVISIBLE (3075 125);
FORCEADD Q_CAPP..1
(3550 -950);
FORCEPROP 1 LAST PART_NUMBER CH733LY8802
J 0
(3600 -1100);
DISPLAY 0.617021 (3600 -1100);
PAINT BLUE (3600 -1100);
DISPLAY INVISIBLE (3600 -1100);
FORCEPROP 1 LAST VALUE 330UF
J 0
(3600 -850);
DISPLAY 0.617021 (3600 -850);
PAINT SKYBLUE (3600 -850);
FORCEPROP 1 LAST TOLERANCE +10/-35%
J 0
(3600 -900);
DISPLAY 0.617021 (3600 -900);
PAINT SKYBLUE (3600 -900);
FORCEPROP 1 LAST VOLTAGE 2.5V
J 0
(3600 -950);
DISPLAY 0.617021 (3600 -950);
PAINT SKYBLUE (3600 -950);
FORCEPROP 1 LAST PACK_TYPE SMLF
J 0
(3600 -1050);
DISPLAY 0.617021 (3600 -1050);
PAINT SKYBLUE (3600 -1050);
FORCEPROP 1 LAST MATERIAL EMPTY
J 0
(3600 -1000);
DISPLAY 0.617021 (3600 -1000);
PAINT RED (3600 -1000);
FORCEPROP 1 LAST LOCATION PC587
J 0
(3600 -800);
DISPLAY 0.617021 (3600 -800);
PAINT AQUA (3600 -800);
FORCEPROP 1 LASTPIN (3550 -850) $PN 1
J 0
(3560 -865);
DISPLAY 0.617021 (3560 -865);
PAINT MONO (3560 -865);
FORCEPROP 1 LASTPIN (3550 -1050) $PN 2
J 0
(3560 -1065);
DISPLAY 0.617021 (3560 -1065);
PAINT MONO (3560 -1065);
FORCEPROP 2 LAST CDS_LIB pure_quanta
J 0
(3550 -950);
DISPLAY INVISIBLE (3550 -950);
FORCEPROP 1 LAST PATH I65
J 0
(3600 -800);
DISPLAY 0.978723 (3600 -800);
DISPLAY INVISIBLE (3600 -800);
FORCEPROP 1 LAST LOCATION PC587
J 0
(3600 -750);
DISPLAY 1.021277 (3600 -750);
PAINT AQUA (3600 -750);
DISPLAY INVISIBLE (3600 -750);
FORCEPROP 0 LAST $SEC 1
J 0
(3600 -750);
DISPLAY 0.680851 (3600 -750);
PAINT MONO (3600 -750);
DISPLAY INVISIBLE (3600 -750);
FORCEPROP 0 LAST CDS_SEC 1
J 0
(3600 -750);
DISPLAY 1.021277 (3600 -750);
DISPLAY INVISIBLE (3600 -750);
FORCEADD VCC15..1
(4075 -1675);
FORCEPROP 3 LASTPIN (4075 -1725) SIG_NAME PVCCIN_CPU1\g
J 0
(4085 -1715);
DISPLAY 0.659574 (4085 -1715);
PAINT MONO (4085 -1715);
DISPLAY INVISIBLE (4085 -1715);
FORCEPROP 1 LAST HDL_POWER PVCCIN_CPU1
J 1
(4075 -1625);
DISPLAY 0.617021 (4075 -1625);
PAINT GREEN (4075 -1625);
FORCEPROP 2 LAST CDS_LIB logical_power
J 0
(4075 -1675);
DISPLAY INVISIBLE (4075 -1675);
FORCEPROP 1 LAST PATH I66
J 0
(4125 -1650);
DISPLAY 0.872340 (4125 -1650);
PAINT AQUA (4125 -1650);
DISPLAY INVISIBLE (4125 -1650);
FORCEADD UNIVERSAL_GND..1
(4050 -1275);
FORCEPROP 3 LASTPIN (4050 -1225) SIG_NAME GND\g
J 0
(4060 -1215);
DISPLAY 0.659574 (4060 -1215);
PAINT MONO (4060 -1215);
DISPLAY INVISIBLE (4060 -1215);
FORCEPROP 1 LAST HDL_POWER GND
J 1
(4075 -1350);
DISPLAY 0.872340 (4075 -1350);
PAINT GREEN (4075 -1350);
DISPLAY INVISIBLE (4075 -1350);
FORCEPROP 2 LAST CDS_LIB logical_power
J 0
(4050 -1275);
PAINT MONO (4050 -1275);
DISPLAY INVISIBLE (4050 -1275);
FORCEPROP 1 LAST PATH I67
J 0
(4125 -1275);
DISPLAY 0.872340 (4125 -1275);
PAINT AQUA (4125 -1275);
DISPLAY INVISIBLE (4125 -1275);
FORCEADD Q_CAPP..1
(4050 -950);
FORCEPROP 1 LAST PART_NUMBER CH733LY8802
J 0
(4100 -1100);
DISPLAY 0.617021 (4100 -1100);
PAINT BLUE (4100 -1100);
DISPLAY INVISIBLE (4100 -1100);
FORCEPROP 1 LAST VOLTAGE 2.5V
J 0
(4100 -950);
DISPLAY 0.617021 (4100 -950);
PAINT SKYBLUE (4100 -950);
FORCEPROP 1 LAST PACK_TYPE SMLF
J 0
(4100 -1050);
DISPLAY 0.617021 (4100 -1050);
PAINT SKYBLUE (4100 -1050);
FORCEPROP 1 LAST MATERIAL EMPTY
J 0
(4100 -1000);
DISPLAY 0.617021 (4100 -1000);
PAINT RED (4100 -1000);
FORCEPROP 1 LAST VALUE 330UF
J 0
(4100 -850);
DISPLAY 0.617021 (4100 -850);
PAINT SKYBLUE (4100 -850);
FORCEPROP 1 LAST TOLERANCE +10/-35%
J 0
(4100 -900);
DISPLAY 0.617021 (4100 -900);
PAINT SKYBLUE (4100 -900);
FORCEPROP 1 LAST LOCATION PC590
J 0
(4100 -800);
DISPLAY 0.617021 (4100 -800);
PAINT AQUA (4100 -800);
FORCEPROP 1 LASTPIN (4050 -850) $PN 1
J 0
(4060 -865);
DISPLAY 0.617021 (4060 -865);
PAINT MONO (4060 -865);
FORCEPROP 1 LASTPIN (4050 -1050) $PN 2
J 0
(4060 -1065);
DISPLAY 0.617021 (4060 -1065);
PAINT MONO (4060 -1065);
FORCEPROP 2 LAST CDS_LIB pure_quanta
J 0
(4050 -950);
DISPLAY INVISIBLE (4050 -950);
FORCEPROP 1 LAST PATH I68
J 0
(4100 -800);
DISPLAY 0.978723 (4100 -800);
DISPLAY INVISIBLE (4100 -800);
FORCEPROP 1 LAST LOCATION PC590
J 0
(4100 -750);
DISPLAY 1.021277 (4100 -750);
PAINT AQUA (4100 -750);
DISPLAY INVISIBLE (4100 -750);
FORCEPROP 0 LAST $SEC 1
J 0
(4100 -750);
DISPLAY 0.680851 (4100 -750);
PAINT MONO (4100 -750);
DISPLAY INVISIBLE (4100 -750);
FORCEPROP 0 LAST CDS_SEC 1
J 0
(4100 -750);
DISPLAY 1.021277 (4100 -750);
DISPLAY INVISIBLE (4100 -750);
FORCEADD Q_CAPP..1
(3550 -75);
FORCEPROP 1 LAST PART_NUMBER CC7560JMD16
J 0
(3600 -225);
DISPLAY 0.617021 (3600 -225);
PAINT BLUE (3600 -225);
DISPLAY INVISIBLE (3600 -225);
FORCEPROP 1 LAST PACK_TYPE THLF
J 0
(3600 -175);
DISPLAY 0.617021 (3600 -175);
PAINT SKYBLUE (3600 -175);
FORCEPROP 1 LAST VALUE 560UF
J 0
(3600 25);
DISPLAY 0.617021 (3600 25);
PAINT SKYBLUE (3600 25);
FORCEPROP 1 LAST TOLERANCE 20%
J 0
(3600 -25);
DISPLAY 0.617021 (3600 -25);
PAINT SKYBLUE (3600 -25);
FORCEPROP 1 LAST MATERIAL OSCON
J 0
(3600 -125);
DISPLAY 0.617021 (3600 -125);
PAINT SKYBLUE (3600 -125);
FORCEPROP 1 LAST VOLTAGE 2.5V
J 0
(3600 -75);
DISPLAY 0.617021 (3600 -75);
PAINT SKYBLUE (3600 -75);
FORCEPROP 1 LAST LOCATION PC586
J 0
(3600 75);
DISPLAY 0.617021 (3600 75);
PAINT AQUA (3600 75);
FORCEPROP 1 LASTPIN (3550 25) $PN 1
J 0
(3560 10);
DISPLAY 0.617021 (3560 10);
PAINT MONO (3560 10);
FORCEPROP 1 LASTPIN (3550 -175) $PN 2
J 0
(3560 -190);
DISPLAY 0.617021 (3560 -190);
PAINT MONO (3560 -190);
FORCEPROP 2 LAST CDS_LIB pure_quanta
J 0
(3550 -75);
DISPLAY INVISIBLE (3550 -75);
FORCEPROP 1 LAST PATH I69
J 0
(3600 75);
DISPLAY 0.978723 (3600 75);
DISPLAY INVISIBLE (3600 75);
FORCEPROP 1 LAST LOCATION PC586
J 0
(3600 125);
DISPLAY 1.021277 (3600 125);
PAINT AQUA (3600 125);
DISPLAY INVISIBLE (3600 125);
FORCEPROP 0 LAST $SEC 1
J 0
(3600 125);
DISPLAY 0.680851 (3600 125);
PAINT MONO (3600 125);
DISPLAY INVISIBLE (3600 125);
FORCEPROP 0 LAST CDS_SEC 1
J 0
(3600 125);
DISPLAY 1.021277 (3600 125);
DISPLAY INVISIBLE (3600 125);
FORCEADD ISL99390FRZTR5935..1
(-2125 -1700);
FORCEPROP 1 LAST PART_NUMBER AL099390004
J 0
(-2425 -900);
DISPLAY 0.617021 (-2425 -900);
PAINT BLUE (-2425 -900);
DISPLAY INVISIBLE (-2425 -900);
FORCEPROP 1 LAST MATERIAL IC
J 0
(-2425 -975);
DISPLAY 0.617021 (-2425 -975);
PAINT SKYBLUE (-2425 -975);
FORCEPROP 2 LAST PART_TYPE SMLF
J 0
(-2425 -700);
DISPLAY 0.638298 (-2425 -700);
FORCEPROP 2 LAST VALUE ISL99390FRZ-TR5935
J 0
(-2425 -750);
DISPLAY 0.617021 (-2425 -750);
PAINT SKYBLUE (-2425 -750);
FORCEPROP 1 LAST LOCATION PU30_P1_2
J 0
(-2425 -825);
DISPLAY 0.617021 (-2425 -825);
PAINT AQUA (-2425 -825);
FORCEPROP 2 LASTPIN (-1725 -2150) $PN 2
J 0
(-1715 -2140);
DISPLAY 0.617021 (-1715 -2140);
PAINT MONO (-1715 -2140);
FORCEPROP 2 LASTPIN (-1725 -1350) $PN 33
J 0
(-1715 -1340);
DISPLAY 0.617021 (-1715 -1340);
PAINT MONO (-1715 -1340);
FORCEPROP 2 LASTPIN (-2575 -1950) $PN 31
J 2
(-2585 -1940);
DISPLAY 0.617021 (-2585 -1940);
PAINT MONO (-2585 -1940);
FORCEPROP 2 LASTPIN (-2575 -1550) $PN 35
J 2
(-2585 -1540);
DISPLAY 0.617021 (-2585 -1540);
PAINT MONO (-2585 -1540);
FORCEPROP 2 LASTPIN (-1725 -2000) $PN 6
J 0
(-1715 -1990);
DISPLAY 0.617021 (-1715 -1990);
PAINT MONO (-1715 -1990);
FORCEPROP 2 LASTPIN (-1725 -2050) $PN 41
J 0
(-1715 -2040);
DISPLAY 0.617021 (-1715 -2040);
PAINT MONO (-1715 -2040);
FORCEPROP 2 LASTPIN (-2575 -1700) $PN 38
J 2
(-2585 -1690);
DISPLAY 0.617021 (-2585 -1690);
PAINT MONO (-2585 -1690);
FORCEPROP 2 LASTPIN (-2575 -2000) $PN 37
J 2
(-2585 -1990);
DISPLAY 0.617021 (-2585 -1990);
PAINT MONO (-2585 -1990);
FORCEPROP 2 LASTPIN (-1725 -2200) $PN 5
J 0
(-1715 -2190);
DISPLAY 0.617021 (-1715 -2190);
PAINT MONO (-1715 -2190);
FORCEPROP 2 LASTPIN (-1725 -2250) $PN 7_9-20_24
J 0
(-1715 -2240);
DISPLAY 0.617021 (-1715 -2240);
PAINT MONO (-1715 -2240);
FORCEPROP 2 LASTPIN (-1725 -2300) $PN 40
J 0
(-1715 -2290);
DISPLAY 0.617021 (-1715 -2290);
PAINT MONO (-1715 -2290);
FORCEPROP 2 LASTPIN (-1725 -1600) $PN 32
J 0
(-1715 -1590);
DISPLAY 0.617021 (-1715 -1590);
PAINT MONO (-1715 -1590);
FORCEPROP 2 LASTPIN (-2575 -1050) $PN 4
J 2
(-2585 -1040);
DISPLAY 0.617021 (-2585 -1040);
PAINT MONO (-2585 -1040);
FORCEPROP 2 LASTPIN (-2575 -2300) $PN 34
J 2
(-2585 -2290);
DISPLAY 0.617021 (-2585 -2290);
PAINT MONO (-2585 -2290);
FORCEPROP 2 LASTPIN (-2575 -1800) $PN 39
J 2
(-2585 -1790);
DISPLAY 0.617021 (-2585 -1790);
PAINT MONO (-2585 -1790);
FORCEPROP 2 LASTPIN (-1725 -1700) $PN 10_19
J 0
(-1715 -1690);
DISPLAY 0.617021 (-1715 -1690);
PAINT MONO (-1715 -1690);
FORCEPROP 2 LASTPIN (-2575 -2200) $PN 36
J 2
(-2585 -2190);
DISPLAY 0.617021 (-2585 -2190);
PAINT MONO (-2585 -2190);
FORCEPROP 2 LASTPIN (-2575 -1350) $PN 3
J 2
(-2585 -1340);
DISPLAY 0.617021 (-2585 -1340);
PAINT MONO (-2585 -1340);
FORCEPROP 2 LASTPIN (-1725 -1050) $PN 25_29
J 0
(-1715 -1040);
DISPLAY 0.617021 (-1715 -1040);
PAINT MONO (-1715 -1040);
FORCEPROP 2 LASTPIN (-1725 -1100) $PN 30
J 0
(-1715 -1090);
DISPLAY 0.617021 (-1715 -1090);
PAINT MONO (-1715 -1090);
FORCEPROP 2 LASTPIN (-1725 -1950) $PN 1
J 0
(-1715 -1940);
DISPLAY 0.617021 (-1715 -1940);
PAINT MONO (-1715 -1940);
FORCEPROP 2 LAST CDS_LIB pure_quanta
J 0
(-2125 -1700);
DISPLAY INVISIBLE (-2125 -1700);
FORCEPROP 1 LAST CDS_LMAN_SYM_OUTLINE -300,700,250,-650
J 0
(-2125 -1700);
DISPLAY 0.468085 (-2125 -1700);
PAINT GREEN (-2125 -1700);
DISPLAY INVISIBLE (-2125 -1700);
FORCEPROP 1 LAST NEEDS_NO_SIZE TRUE
J 0
(-2125 -1700);
DISPLAY 0.723404 (-2125 -1700);
PAINT GREEN (-2125 -1700);
DISPLAY INVISIBLE (-2125 -1700);
FORCEPROP 1 LAST PATH I7
J 0
(-2125 -1700);
DISPLAY 0.723404 (-2125 -1700);
PAINT GREEN (-2125 -1700);
DISPLAY INVISIBLE (-2125 -1700);
FORCEPROP 2 LAST $SEC 1
J 0
(-2425 -775);
DISPLAY 0.680851 (-2425 -775);
PAINT MONO (-2425 -775);
DISPLAY INVISIBLE (-2425 -775);
FORCEPROP 2 LAST CDS_SEC 1
J 0
(-2425 -775);
DISPLAY 1.021277 (-2425 -775);
DISPLAY INVISIBLE (-2425 -775);
FORCEADD VCC15..1
(4050 -625);
FORCEPROP 3 LASTPIN (4050 -675) SIG_NAME PVCCIN_CPU1\g
J 0
(4060 -665);
DISPLAY 0.659574 (4060 -665);
PAINT MONO (4060 -665);
DISPLAY INVISIBLE (4060 -665);
FORCEPROP 1 LAST HDL_POWER PVCCIN_CPU1
J 1
(4050 -575);
DISPLAY 0.617021 (4050 -575);
PAINT GREEN (4050 -575);
FORCEPROP 2 LAST CDS_LIB logical_power
J 0
(4050 -625);
DISPLAY INVISIBLE (4050 -625);
FORCEPROP 1 LAST PATH I70
J 0
(4100 -600);
DISPLAY 0.872340 (4100 -600);
PAINT AQUA (4100 -600);
DISPLAY INVISIBLE (4100 -600);
FORCEADD UNIVERSAL_GND..1
(4050 -400);
FORCEPROP 3 LASTPIN (4050 -350) SIG_NAME GND\g
J 0
(4060 -340);
DISPLAY 0.659574 (4060 -340);
PAINT MONO (4060 -340);
DISPLAY INVISIBLE (4060 -340);
FORCEPROP 1 LAST HDL_POWER GND
J 1
(4075 -475);
DISPLAY 0.872340 (4075 -475);
PAINT GREEN (4075 -475);
DISPLAY INVISIBLE (4075 -475);
FORCEPROP 2 LAST CDS_LIB logical_power
J 0
(4050 -400);
PAINT MONO (4050 -400);
DISPLAY INVISIBLE (4050 -400);
FORCEPROP 1 LAST PATH I71
J 0
(4125 -400);
DISPLAY 0.872340 (4125 -400);
PAINT AQUA (4125 -400);
DISPLAY INVISIBLE (4125 -400);
FORCEADD Q_CAPP..1
(4050 -75);
FORCEPROP 1 LAST PART_NUMBER CC7560JMD16
J 0
(4100 -225);
DISPLAY 0.617021 (4100 -225);
PAINT BLUE (4100 -225);
DISPLAY INVISIBLE (4100 -225);
FORCEPROP 1 LAST PACK_TYPE THLF
J 0
(4100 -175);
DISPLAY 0.617021 (4100 -175);
PAINT SKYBLUE (4100 -175);
FORCEPROP 1 LAST VALUE 560UF
J 0
(4100 25);
DISPLAY 0.617021 (4100 25);
PAINT SKYBLUE (4100 25);
FORCEPROP 1 LAST TOLERANCE 20%
J 0
(4100 -25);
DISPLAY 0.617021 (4100 -25);
PAINT SKYBLUE (4100 -25);
FORCEPROP 1 LAST MATERIAL OSCON
J 0
(4100 -125);
DISPLAY 0.617021 (4100 -125);
PAINT SKYBLUE (4100 -125);
FORCEPROP 1 LAST VOLTAGE 2.5V
J 0
(4100 -75);
DISPLAY 0.617021 (4100 -75);
PAINT SKYBLUE (4100 -75);
FORCEPROP 1 LAST LOCATION PC589
J 0
(4100 75);
DISPLAY 0.617021 (4100 75);
PAINT AQUA (4100 75);
FORCEPROP 1 LASTPIN (4050 25) $PN 1
J 0
(4060 10);
DISPLAY 0.617021 (4060 10);
PAINT MONO (4060 10);
FORCEPROP 1 LASTPIN (4050 -175) $PN 2
J 0
(4060 -190);
DISPLAY 0.617021 (4060 -190);
PAINT MONO (4060 -190);
FORCEPROP 2 LAST CDS_LIB pure_quanta
J 0
(4050 -75);
DISPLAY INVISIBLE (4050 -75);
FORCEPROP 1 LAST PATH I72
J 0
(4100 75);
DISPLAY 0.978723 (4100 75);
DISPLAY INVISIBLE (4100 75);
FORCEPROP 1 LAST LOCATION PC589
J 0
(4100 125);
DISPLAY 1.021277 (4100 125);
PAINT AQUA (4100 125);
DISPLAY INVISIBLE (4100 125);
FORCEPROP 0 LAST $SEC 1
J 0
(4100 125);
DISPLAY 0.680851 (4100 125);
PAINT MONO (4100 125);
DISPLAY INVISIBLE (4100 125);
FORCEPROP 0 LAST CDS_SEC 1
J 0
(4100 125);
DISPLAY 1.021277 (4100 125);
DISPLAY INVISIBLE (4100 125);
FORCEADD Q_RES..1
(175 600);
FORCEPROP 1 LAST PART_NUMBER CS00002JB13
J 0
(50 650);
DISPLAY 0.617021 (50 650);
PAINT BLUE (50 650);
DISPLAY INVISIBLE (50 650);
FORCEPROP 1 LAST MATERIAL CHIP
J 0
(450 600);
DISPLAY 0.617021 (450 600);
PAINT SKYBLUE (450 600);
FORCEPROP 1 LAST PACK_TYPE 0402LF
J 0
(50 700);
DISPLAY 0.617021 (50 700);
PAINT SKYBLUE (50 700);
FORCEPROP 1 LAST TOLERANCE 5%
J 0
(375 600);
DISPLAY 0.617021 (375 600);
PAINT SKYBLUE (375 600);
FORCEPROP 1 LAST VALUE 0
J 2
(350 600);
DISPLAY 0.617021 (350 600);
PAINT SKYBLUE (350 600);
FORCEPROP 1 LAST WATTAGE 1/16W
J 2
(425 700);
DISPLAY 0.617021 (425 700);
PAINT SKYBLUE (425 700);
FORCEPROP 1 LAST LOCATION PR330
J 0
(-100 600);
DISPLAY 0.617021 (-100 600);
PAINT AQUA (-100 600);
FORCEPROP 1 LASTPIN (75 600) $PN 1
J 0
(87 612);
DISPLAY 0.617021 (87 612);
PAINT MONO (87 612);
FORCEPROP 1 LASTPIN (275 600) $PN 2
J 0
(237 612);
DISPLAY 0.617021 (237 612);
PAINT MONO (237 612);
FORCEPROP 2 LAST CDS_LIB pure_quanta
J 0
(175 600);
DISPLAY INVISIBLE (175 600);
FORCEPROP 1 LAST PATH I73
J 0
(125 750);
DISPLAY 0.978723 (125 750);
PAINT WHITE (125 750);
DISPLAY INVISIBLE (125 750);
FORCEPROP 0 LAST $SEC 1
J 0
(425 750);
DISPLAY 0.680851 (425 750);
PAINT MONO (425 750);
DISPLAY INVISIBLE (425 750);
FORCEPROP 0 LAST CDS_SEC 1
J 0
(425 750);
DISPLAY 1.021277 (425 750);
DISPLAY INVISIBLE (425 750);
FORCEADD Q_INDUCTOR4P_14..1
(775 1025);
FORCEPROP 1 LAST PART_NUMBER CV+15^0TZ04
J 0
(550 1185);
DISPLAY 0.617021 (550 1185);
PAINT BLUE (550 1185);
DISPLAY INVISIBLE (550 1185);
FORCEPROP 2 LAST PART_TYPE SMLF
J 0
(550 1375);
DISPLAY 1.021277 (550 1375);
FORCEPROP 1 LAST MATERIAL IND
J 0
(550 1235);
DISPLAY 0.617021 (550 1235);
PAINT SKYBLUE (550 1235);
FORCEPROP 2 LAST VALUE 150NH
J 0
(550 1325);
DISPLAY 0.617021 (550 1325);
PAINT SKYBLUE (550 1325);
FORCEPROP 1 LAST LOCATION PL31
J 0
(550 1280);
DISPLAY 0.617021 (550 1280);
PAINT AQUA (550 1280);
FORCEPROP 2 LASTPIN (375 1150) $PN 1
J 2
(365 1160);
DISPLAY 0.617021 (365 1160);
PAINT MONO (365 1160);
FORCEPROP 2 LASTPIN (375 900) $PN 2
J 2
(365 910);
DISPLAY 0.617021 (365 910);
PAINT MONO (365 910);
FORCEPROP 2 LASTPIN (1175 900) $PN 3
J 0
(1185 910);
DISPLAY 0.617021 (1185 910);
PAINT MONO (1185 910);
FORCEPROP 2 LASTPIN (1175 1150) $PN 4
J 0
(1185 1160);
DISPLAY 0.617021 (1185 1160);
PAINT MONO (1185 1160);
FORCEPROP 2 LAST SEC_TYPE 
J 0
(550 1425);
DISPLAY 1.021277 (550 1425);
DISPLAY INVISIBLE (550 1425);
FORCEPROP 2 LAST CDS_LIB pure_quanta
J 0
(775 1025);
DISPLAY INVISIBLE (775 1025);
FORCEPROP 1 LAST NEEDS_NO_SIZE TRUE
J 0
(775 1025);
DISPLAY 0.468085 (775 1025);
PAINT GREEN (775 1025);
DISPLAY INVISIBLE (775 1025);
FORCEPROP 1 LAST PATH I74
J 0
(975 1180);
DISPLAY 0.723404 (975 1180);
PAINT GREEN (975 1180);
DISPLAY INVISIBLE (975 1180);
FORCEPROP 2 LAST SEC 1
J 0
(550 1425);
DISPLAY 0.680851 (550 1425);
PAINT MONO (550 1425);
DISPLAY INVISIBLE (550 1425);
FORCEADD UNIVERSAL_GND..1
(500 1600);
FORCEPROP 3 LASTPIN (500 1650) SIG_NAME GND\g
J 0
(510 1660);
DISPLAY 0.659574 (510 1660);
PAINT MONO (510 1660);
DISPLAY INVISIBLE (510 1660);
FORCEPROP 1 LAST HDL_POWER GND
J 1
(525 1525);
DISPLAY 0.872340 (525 1525);
PAINT GREEN (525 1525);
DISPLAY INVISIBLE (525 1525);
FORCEPROP 2 LAST CDS_LIB logical_power
J 0
(500 1600);
PAINT MONO (500 1600);
DISPLAY INVISIBLE (500 1600);
FORCEPROP 1 LAST PATH I75
J 0
(575 1600);
DISPLAY 0.872340 (575 1600);
PAINT AQUA (575 1600);
DISPLAY INVISIBLE (575 1600);
FORCEADD Q_CAP..1
(275 2025);
FORCEPROP 1 LAST PART_NUMBER CH6223MEA01
J 0
(325 1875);
DISPLAY 0.617021 (325 1875);
PAINT BLUE (325 1875);
DISPLAY INVISIBLE (325 1875);
FORCEPROP 1 LAST TOLERANCE 20%
J 0
(325 2025);
DISPLAY 0.617021 (325 2025);
PAINT SKYBLUE (325 2025);
FORCEPROP 1 LAST MATERIAL X6S
J 0
(325 1975);
DISPLAY 0.617021 (325 1975);
PAINT SKYBLUE (325 1975);
FORCEPROP 1 LAST PACK_TYPE C0805
J 0
(325 1925);
DISPLAY 0.617021 (325 1925);
PAINT SKYBLUE (325 1925);
FORCEPROP 1 LAST VOLTAGE 16V
J 0
(325 2075);
DISPLAY 0.617021 (325 2075);
PAINT SKYBLUE (325 2075);
FORCEPROP 1 LAST VALUE 22UF
J 0
(325 2125);
DISPLAY 0.617021 (325 2125);
PAINT SKYBLUE (325 2125);
FORCEPROP 1 LAST LOCATION PC571_P1_1
J 0
(325 2175);
DISPLAY 0.617021 (325 2175);
PAINT AQUA (325 2175);
FORCEPROP 1 LASTPIN (275 2125) $PN 1
J 0
(285 2105);
DISPLAY 0.617021 (285 2105);
PAINT MONO (285 2105);
FORCEPROP 1 LASTPIN (275 1925) $PN 2
J 0
(285 1905);
DISPLAY 0.617021 (285 1905);
PAINT MONO (285 1905);
FORCEPROP 2 LAST CDS_LIB pure_quanta
J 0
(275 2025);
DISPLAY INVISIBLE (275 2025);
FORCEPROP 1 LAST PATH I76
J 0
(325 2175);
DISPLAY 0.978723 (325 2175);
PAINT WHITE (325 2175);
DISPLAY INVISIBLE (325 2175);
FORCEPROP 1 LAST LOCATION PC571_P1_1
J 0
(325 2225);
DISPLAY 1.021277 (325 2225);
PAINT AQUA (325 2225);
DISPLAY INVISIBLE (325 2225);
FORCEPROP 0 LAST $SEC 1
J 0
(325 2225);
DISPLAY 0.680851 (325 2225);
PAINT MONO (325 2225);
DISPLAY INVISIBLE (325 2225);
FORCEPROP 0 LAST CDS_SEC 1
J 0
(325 2225);
DISPLAY 1.021277 (325 2225);
DISPLAY INVISIBLE (325 2225);
FORCEADD OFFPAGE..3
(1750 900);
FORCEPROP 2 LAST $XR0 287 
J 0
(1964 900);
DISPLAY 0.638298 (1964 900);
PAINT MONO (1964 900);
FORCEPROP 1 LAST COMMENT_BODY TRUE
J 0
(1700 800);
DISPLAY 0.872340 (1700 800);
PAINT GREEN (1700 800);
DISPLAY INVISIBLE (1700 800);
FORCEPROP 1 LAST OFFPAGE TRUE
J 0
(2075 775);
DISPLAY 0.872340 (2075 775);
PAINT GREEN (2075 775);
DISPLAY INVISIBLE (2075 775);
FORCEPROP 2 LAST CDS_LIB standard
J 0
(1750 900);
DISPLAY INVISIBLE (1750 900);
FORCEPROP 2 LAST PATH I77
J 0
(1975 950);
DISPLAY 1.021277 (1975 950);
DISPLAY INVISIBLE (1975 950);
FORCEADD GND..1
(1400 2000);
FORCEPROP 3 LASTPIN (1400 2050) SIG_NAME GND\g
J 0
(1410 2060);
DISPLAY 0.659574 (1410 2060);
PAINT MONO (1410 2060);
DISPLAY INVISIBLE (1410 2060);
FORCEPROP 1 LAST HDL_POWER GND
J 0
(1400 2150);
DISPLAY 0.872340 (1400 2150);
PAINT GREEN (1400 2150);
DISPLAY INVISIBLE (1400 2150);
FORCEPROP 1 LAST SIZE 1B
J 0
(1475 1950);
DISPLAY 0.872340 (1475 1950);
PAINT AQUA (1475 1950);
DISPLAY INVISIBLE (1475 1950);
FORCEPROP 2 LAST CDS_LIB logical_power
J 0
(1400 2000);
DISPLAY INVISIBLE (1400 2000);
FORCEPROP 1 LAST PATH I78
J 0
(1475 2000);
DISPLAY 0.872340 (1475 2000);
PAINT AQUA (1475 2000);
DISPLAY INVISIBLE (1475 2000);
FORCEADD Q_CAP..1
R 2
(1400 2250);
FORCEPROP 1 LAST PART_NUMBER CH4106K1B01
J 2
(1350 2100);
DISPLAY 0.787234 (1350 2100);
DISPLAY INVISIBLE (1350 2100);
FORCEPROP 1 LAST TOLERANCE 10%
J 2
(1350 2200);
DISPLAY 0.787234 (1350 2200);
FORCEPROP 1 LAST PACK_TYPE C0402
J 2
(1350 2050);
DISPLAY 0.787234 (1350 2050);
FORCEPROP 1 LAST MATERIAL X7R
J 2
(1350 2150);
DISPLAY 0.787234 (1350 2150);
FORCEPROP 1 LAST VOLTAGE 50V
J 2
(1350 2250);
DISPLAY 0.787234 (1350 2250);
FORCEPROP 1 LAST VALUE 100NF
J 2
(1350 2300);
DISPLAY 0.787234 (1350 2300);
FORCEPROP 1 LAST LOCATION PC1656
J 2
(1350 2350);
DISPLAY 0.787234 (1350 2350);
FORCEPROP 1 LASTPIN (1400 2350) $PN 1
J 2
(1390 2330);
DISPLAY 0.787234 (1390 2330);
PAINT MONO (1390 2330);
FORCEPROP 1 LASTPIN (1400 2150) $PN 2
J 2
(1390 2130);
DISPLAY 0.787234 (1390 2130);
PAINT MONO (1390 2130);
FORCEPROP 2 LAST CDS_LIB pure_quanta
J 2
(1400 2250);
DISPLAY INVISIBLE (1400 2250);
FORCEPROP 1 LAST PATH I79
J 2
(1350 2400);
DISPLAY 0.978723 (1350 2400);
PAINT WHITE (1350 2400);
DISPLAY INVISIBLE (1350 2400);
FORCEPROP 0 LAST $SEC 1
J 2
(1350 2400);
DISPLAY 0.680851 (1350 2400);
PAINT MONO (1350 2400);
DISPLAY INVISIBLE (1350 2400);
FORCEPROP 0 LAST CDS_SEC 1
J 2
(1350 2400);
DISPLAY 1.021277 (1350 2400);
DISPLAY INVISIBLE (1350 2400);
FORCEADD OFFPAGE..5
(-3575 -1700);
FORCEPROP 2 LAST $XR0 284 
J 0
(-3830 -1700);
DISPLAY 0.638298 (-3830 -1700);
PAINT MONO (-3830 -1700);
FORCEPROP 1 LAST COMMENT_BODY TRUE
J 0
(-3475 -1775);
DISPLAY 0.872340 (-3475 -1775);
PAINT GREEN (-3475 -1775);
DISPLAY INVISIBLE (-3475 -1775);
FORCEPROP 1 LAST OFFPAGE TRUE
J 0
(-3250 -1825);
DISPLAY 0.872340 (-3250 -1825);
PAINT GREEN (-3250 -1825);
DISPLAY INVISIBLE (-3250 -1825);
FORCEPROP 2 LAST CDS_LIB standard
J 0
(-3575 -1700);
DISPLAY INVISIBLE (-3575 -1700);
FORCEPROP 2 LAST PATH I8
J 0
(-3825 -1650);
DISPLAY 1.021277 (-3825 -1650);
DISPLAY INVISIBLE (-3825 -1650);
FORCEADD VCC15..1
(500 2400);
FORCEPROP 3 LASTPIN (500 2350) SIG_NAME SW_P12V_PVCCIN_CPU1_FLT\g
J 0
(510 2360);
DISPLAY 0.659574 (510 2360);
PAINT MONO (510 2360);
DISPLAY INVISIBLE (510 2360);
FORCEPROP 1 LAST HDL_POWER SW_P12V_PVCCIN_CPU1_FLT
J 1
(550 2450);
DISPLAY 0.617021 (550 2450);
PAINT GREEN (550 2450);
FORCEPROP 2 LAST CDS_LIB logical_power
J 0
(500 2400);
DISPLAY INVISIBLE (500 2400);
FORCEPROP 1 LAST PATH I80
J 0
(550 2425);
DISPLAY 0.872340 (550 2425);
PAINT AQUA (550 2425);
DISPLAY INVISIBLE (550 2425);
FORCEADD VCC15..1
(1400 2625);
FORCEPROP 3 LASTPIN (1400 2575) SIG_NAME P12V_AUX\g
J 0
(1410 2585);
DISPLAY 0.659574 (1410 2585);
PAINT MONO (1410 2585);
DISPLAY INVISIBLE (1410 2585);
FORCEPROP 1 LAST HDL_POWER P12V_AUX
J 1
(1400 2675);
DISPLAY 0.617021 (1400 2675);
PAINT GREEN (1400 2675);
FORCEPROP 2 LAST CDS_LIB logical_power
J 0
(1400 2625);
DISPLAY INVISIBLE (1400 2625);
FORCEPROP 1 LAST PATH I81
J 0
(1450 2650);
DISPLAY 0.872340 (1450 2650);
PAINT AQUA (1450 2650);
DISPLAY INVISIBLE (1450 2650);
FORCEADD Q_RES..1
(1925 2325);
FORCEPROP 1 LAST PART_NUMBER TMP_QCS+0308BR00
J 0
(1750 2250);
DISPLAY 0.638298 (1750 2250);
DISPLAY INVISIBLE (1750 2250);
FORCEPROP 1 LAST PACK_TYPE 2512LF
J 0
(1750 2175);
DISPLAY 0.638298 (1750 2175);
FORCEPROP 1 LAST MATERIAL EMPTY
J 0
(2075 2175);
DISPLAY 0.638298 (2075 2175);
PAINT RED (2075 2175);
FORCEPROP 1 LAST WATTAGE 1W
J 2
(2025 2175);
DISPLAY 0.638298 (2025 2175);
FORCEPROP 1 LAST VALUE 0.03
J 2
(2150 2325);
DISPLAY 0.638298 (2150 2325);
FORCEPROP 1 LAST TOLERANCE 0.1%
J 0
(2175 2325);
DISPLAY 0.638298 (2175 2325);
FORCEPROP 1 LAST LOCATION PR2556
J 0
(1650 2325);
DISPLAY 0.510638 (1650 2325);
FORCEPROP 1 LASTPIN (1825 2325) $PN 1
J 0
(1837 2337);
DISPLAY 0.787234 (1837 2337);
PAINT MONO (1837 2337);
FORCEPROP 1 LASTPIN (2025 2325) $PN 2
J 0
(1987 2337);
DISPLAY 0.787234 (1987 2337);
PAINT MONO (1987 2337);
FORCEPROP 2 LAST CDS_LIB pure_quanta
J 0
(1925 2325);
DISPLAY INVISIBLE (1925 2325);
FORCEPROP 1 LAST PATH I82
J 0
(1875 2475);
DISPLAY 0.978723 (1875 2475);
PAINT WHITE (1875 2475);
DISPLAY INVISIBLE (1875 2475);
FORCEPROP 0 LAST $SEC 1
J 0
(2175 2375);
DISPLAY 0.680851 (2175 2375);
PAINT MONO (2175 2375);
DISPLAY INVISIBLE (2175 2375);
FORCEPROP 0 LAST CDS_SEC 1
J 0
(2175 2375);
DISPLAY 1.021277 (2175 2375);
DISPLAY INVISIBLE (2175 2375);
FORCEADD Q_INDUCTOR..1
(1925 2475);
FORCEPROP 1 LAST PART_NUMBER CVA50^0EZ01
J 0
(1800 2585);
DISPLAY 0.617021 (1800 2585);
PAINT BLUE (1800 2585);
DISPLAY INVISIBLE (1800 2585);
FORCEPROP 2 LAST PACK_TYPE SMLF
J 0
(1800 2700);
DISPLAY 0.617021 (1800 2700);
PAINT SKYBLUE (1800 2700);
FORCEPROP 2 LAST VALUE 50NH/148A
J 0
(1800 2650);
DISPLAY 0.617021 (1800 2650);
PAINT SKYBLUE (1800 2650);
FORCEPROP 1 LAST MATERIAL IND
J 0
(1800 2530);
DISPLAY 0.617021 (1800 2530);
PAINT SKYBLUE (1800 2530);
FORCEPROP 1 LAST LOCATION PL32
J 0
(1650 2450);
DISPLAY 0.617021 (1650 2450);
PAINT AQUA (1650 2450);
FORCEPROP 2 LASTPIN (1825 2450) $PN 1
J 2
(1815 2460);
DISPLAY 0.617021 (1815 2460);
FORCEPROP 2 LASTPIN (2025 2450) $PN 2
J 0
(2035 2460);
DISPLAY 0.617021 (2035 2460);
FORCEPROP 1 LAST NEEDS_NO_SIZE TRUE
J 0
(1925 2475);
DISPLAY 0.468085 (1925 2475);
PAINT GREEN (1925 2475);
DISPLAY INVISIBLE (1925 2475);
FORCEPROP 2 LAST CDS_LIB pure_quanta
J 0
(1925 2475);
PAINT MONO (1925 2475);
DISPLAY INVISIBLE (1925 2475);
FORCEPROP 1 LAST PATH I83
J 0
(2000 2530);
DISPLAY 0.723404 (2000 2530);
PAINT GREEN (2000 2530);
DISPLAY INVISIBLE (2000 2530);
FORCEPROP 2 LAST $SEC 1
J 0
(1800 2750);
DISPLAY 0.680851 (1800 2750);
PAINT MONO (1800 2750);
DISPLAY INVISIBLE (1800 2750);
FORCEPROP 0 LAST CDS_SEC 1
J 0
(1900 2575);
DISPLAY 1.021277 (1900 2575);
DISPLAY INVISIBLE (1900 2575);
FORCEADD Q_CAP..1
(2550 950);
FORCEPROP 1 LAST PART_NUMBER CH4106K1B01
J 0
(2600 775);
DISPLAY 0.617021 (2600 775);
PAINT BLUE (2600 775);
DISPLAY INVISIBLE (2600 775);
FORCEPROP 1 LAST VOLTAGE 50V
J 0
(2600 975);
DISPLAY 0.617021 (2600 975);
PAINT SKYBLUE (2600 975);
FORCEPROP 1 LAST VALUE 100NF
J 0
(2600 1025);
DISPLAY 0.617021 (2600 1025);
PAINT SKYBLUE (2600 1025);
FORCEPROP 1 LAST TOLERANCE 10%
J 0
(2600 925);
DISPLAY 0.617021 (2600 925);
PAINT SKYBLUE (2600 925);
FORCEPROP 1 LAST MATERIAL X7R
J 0
(2600 875);
DISPLAY 0.617021 (2600 875);
PAINT SKYBLUE (2600 875);
FORCEPROP 1 LAST PACK_TYPE C0402
J 0
(2600 825);
DISPLAY 0.617021 (2600 825);
PAINT SKYBLUE (2600 825);
FORCEPROP 1 LAST LOCATION PC572_P1_1
J 0
(2600 1075);
DISPLAY 0.617021 (2600 1075);
PAINT AQUA (2600 1075);
FORCEPROP 1 LASTPIN (2550 1050) $PN 1
J 0
(2560 1030);
DISPLAY 0.617021 (2560 1030);
PAINT MONO (2560 1030);
FORCEPROP 1 LASTPIN (2550 850) $PN 2
J 0
(2560 830);
DISPLAY 0.617021 (2560 830);
PAINT MONO (2560 830);
FORCEPROP 2 LAST CDS_LIB pure_quanta
J 0
(2550 950);
DISPLAY INVISIBLE (2550 950);
FORCEPROP 1 LAST PATH I84
J 0
(2600 1100);
DISPLAY 0.978723 (2600 1100);
PAINT WHITE (2600 1100);
DISPLAY INVISIBLE (2600 1100);
FORCEPROP 1 LAST LOCATION PC572_P1_1
J 0
(2600 1125);
DISPLAY 1.021277 (2600 1125);
PAINT AQUA (2600 1125);
DISPLAY INVISIBLE (2600 1125);
FORCEPROP 0 LAST $SEC 1
J 0
(2600 1125);
DISPLAY 0.680851 (2600 1125);
PAINT MONO (2600 1125);
DISPLAY INVISIBLE (2600 1125);
FORCEPROP 0 LAST CDS_SEC 1
J 0
(2600 1125);
DISPLAY 1.021277 (2600 1125);
DISPLAY INVISIBLE (2600 1125);
FORCEADD Q_CAP..1
(2950 950);
FORCEPROP 1 LAST PART_NUMBER CH5103KEB01
J 0
(3000 775);
DISPLAY 0.617021 (3000 775);
PAINT BLUE (3000 775);
DISPLAY INVISIBLE (3000 775);
FORCEPROP 1 LAST TOLERANCE 10%
J 0
(3000 925);
DISPLAY 0.617021 (3000 925);
PAINT SKYBLUE (3000 925);
FORCEPROP 1 LAST VALUE 1UF
J 0
(3000 1025);
DISPLAY 0.617021 (3000 1025);
PAINT SKYBLUE (3000 1025);
FORCEPROP 1 LAST VOLTAGE 16V
J 0
(3000 975);
DISPLAY 0.617021 (3000 975);
PAINT SKYBLUE (3000 975);
FORCEPROP 1 LAST PACK_TYPE C0402
J 0
(3000 825);
DISPLAY 0.617021 (3000 825);
PAINT SKYBLUE (3000 825);
FORCEPROP 1 LAST MATERIAL X6S
J 0
(3000 875);
DISPLAY 0.617021 (3000 875);
PAINT SKYBLUE (3000 875);
FORCEPROP 1 LAST LOCATION PC574_P1_1
J 0
(3000 1075);
DISPLAY 0.617021 (3000 1075);
PAINT AQUA (3000 1075);
FORCEPROP 1 LASTPIN (2950 1050) $PN 1
J 0
(2960 1030);
DISPLAY 0.617021 (2960 1030);
PAINT MONO (2960 1030);
FORCEPROP 1 LASTPIN (2950 850) $PN 2
J 0
(2960 830);
DISPLAY 0.617021 (2960 830);
PAINT MONO (2960 830);
FORCEPROP 2 LAST CDS_LIB pure_quanta
J 0
(2950 950);
DISPLAY INVISIBLE (2950 950);
FORCEPROP 1 LAST PATH I85
J 0
(3000 1100);
DISPLAY 0.978723 (3000 1100);
PAINT WHITE (3000 1100);
DISPLAY INVISIBLE (3000 1100);
FORCEPROP 1 LAST LOCATION PC574_P1_1
J 0
(3000 1125);
DISPLAY 1.021277 (3000 1125);
PAINT AQUA (3000 1125);
DISPLAY INVISIBLE (3000 1125);
FORCEPROP 0 LAST $SEC 1
J 0
(3000 1125);
DISPLAY 0.680851 (3000 1125);
PAINT MONO (3000 1125);
DISPLAY INVISIBLE (3000 1125);
FORCEPROP 0 LAST CDS_SEC 1
J 0
(3000 1125);
DISPLAY 1.021277 (3000 1125);
DISPLAY INVISIBLE (3000 1125);
FORCEADD Q_CAPP..1
(2500 2250);
FORCEPROP 1 LAST PART_NUMBER CC72703MD38
J 0
(2550 2075);
DISPLAY 0.617021 (2550 2075);
PAINT BLUE (2550 2075);
DISPLAY INVISIBLE (2550 2075);
FORCEPROP 1 LAST VALUE 270UF
J 0
(2550 2325);
DISPLAY 0.617021 (2550 2325);
PAINT SKYBLUE (2550 2325);
FORCEPROP 1 LAST TOLERANCE 20%
J 0
(2550 2275);
DISPLAY 0.617021 (2550 2275);
PAINT SKYBLUE (2550 2275);
FORCEPROP 1 LAST VOLTAGE 16V
J 0
(2550 2225);
DISPLAY 0.617021 (2550 2225);
PAINT SKYBLUE (2550 2225);
FORCEPROP 1 LAST MATERIAL OSCON
J 0
(2550 2175);
DISPLAY 0.617021 (2550 2175);
PAINT SKYBLUE (2550 2175);
FORCEPROP 1 LAST PACK_TYPE THLF
J 0
(2550 2125);
DISPLAY 0.617021 (2550 2125);
PAINT SKYBLUE (2550 2125);
FORCEPROP 1 LAST LOCATION PC579
J 0
(2550 2375);
DISPLAY 0.617021 (2550 2375);
PAINT AQUA (2550 2375);
FORCEPROP 1 LASTPIN (2500 2350) $PN 1
J 0
(2510 2335);
DISPLAY 0.617021 (2510 2335);
PAINT MONO (2510 2335);
FORCEPROP 1 LASTPIN (2500 2150) $PN 2
J 0
(2510 2135);
DISPLAY 0.617021 (2510 2135);
PAINT MONO (2510 2135);
FORCEPROP 2 LAST CDS_LIB pure_quanta
J 0
(2500 2250);
DISPLAY INVISIBLE (2500 2250);
FORCEPROP 1 LAST PATH I86
J 0
(2550 2400);
DISPLAY 0.978723 (2550 2400);
DISPLAY INVISIBLE (2550 2400);
FORCEPROP 1 LAST LOCATION PC579
J 0
(2550 2425);
DISPLAY 1.021277 (2550 2425);
PAINT AQUA (2550 2425);
DISPLAY INVISIBLE (2550 2425);
FORCEPROP 0 LAST $SEC 1
J 0
(2550 2425);
DISPLAY 0.680851 (2550 2425);
PAINT MONO (2550 2425);
DISPLAY INVISIBLE (2550 2425);
FORCEPROP 0 LAST CDS_SEC 1
J 0
(2550 2425);
DISPLAY 1.021277 (2550 2425);
DISPLAY INVISIBLE (2550 2425);
FORCEADD Q_CAPP..1
(2900 2250);
FORCEPROP 1 LAST PART_NUMBER CC72703MD38
J 0
(2950 2075);
DISPLAY 0.617021 (2950 2075);
PAINT BLUE (2950 2075);
DISPLAY INVISIBLE (2950 2075);
FORCEPROP 1 LAST VOLTAGE 16V
J 0
(2950 2225);
DISPLAY 0.617021 (2950 2225);
PAINT SKYBLUE (2950 2225);
FORCEPROP 1 LAST TOLERANCE 20%
J 0
(2950 2275);
DISPLAY 0.617021 (2950 2275);
PAINT SKYBLUE (2950 2275);
FORCEPROP 1 LAST MATERIAL OSCON
J 0
(2950 2175);
DISPLAY 0.617021 (2950 2175);
PAINT SKYBLUE (2950 2175);
FORCEPROP 1 LAST PACK_TYPE THLF
J 0
(2950 2125);
DISPLAY 0.617021 (2950 2125);
PAINT SKYBLUE (2950 2125);
FORCEPROP 1 LAST VALUE 270UF
J 0
(2950 2325);
DISPLAY 0.617021 (2950 2325);
PAINT SKYBLUE (2950 2325);
FORCEPROP 1 LAST LOCATION PC582
J 0
(2950 2375);
DISPLAY 0.617021 (2950 2375);
PAINT AQUA (2950 2375);
FORCEPROP 1 LASTPIN (2900 2350) $PN 1
J 0
(2910 2335);
DISPLAY 0.617021 (2910 2335);
PAINT MONO (2910 2335);
FORCEPROP 1 LASTPIN (2900 2150) $PN 2
J 0
(2910 2135);
DISPLAY 0.617021 (2910 2135);
PAINT MONO (2910 2135);
FORCEPROP 2 LAST CDS_LIB pure_quanta
J 0
(2900 2250);
DISPLAY INVISIBLE (2900 2250);
FORCEPROP 1 LAST PATH I87
J 0
(2950 2400);
DISPLAY 0.978723 (2950 2400);
DISPLAY INVISIBLE (2950 2400);
FORCEPROP 1 LAST LOCATION PC582
J 0
(2950 2425);
DISPLAY 1.021277 (2950 2425);
PAINT AQUA (2950 2425);
DISPLAY INVISIBLE (2950 2425);
FORCEPROP 0 LAST $SEC 1
J 0
(2950 2425);
DISPLAY 0.680851 (2950 2425);
PAINT MONO (2950 2425);
DISPLAY INVISIBLE (2950 2425);
FORCEPROP 0 LAST CDS_SEC 1
J 0
(2950 2425);
DISPLAY 1.021277 (2950 2425);
DISPLAY INVISIBLE (2950 2425);
FORCEADD Q_CAP..1
(3375 950);
FORCEPROP 1 LAST PART_NUMBER CH622KMEA03
J 0
(3425 775);
DISPLAY 0.617021 (3425 775);
PAINT BLUE (3425 775);
DISPLAY INVISIBLE (3425 775);
FORCEPROP 1 LAST VOLTAGE 4V
J 0
(3425 975);
DISPLAY 0.617021 (3425 975);
PAINT SKYBLUE (3425 975);
FORCEPROP 1 LAST TOLERANCE 20%
J 0
(3425 925);
DISPLAY 0.617021 (3425 925);
PAINT SKYBLUE (3425 925);
FORCEPROP 1 LAST VALUE 22UF
J 0
(3425 1025);
DISPLAY 0.617021 (3425 1025);
PAINT SKYBLUE (3425 1025);
FORCEPROP 1 LAST MATERIAL X6S
J 0
(3425 875);
DISPLAY 0.617021 (3425 875);
PAINT SKYBLUE (3425 875);
FORCEPROP 1 LAST PACK_TYPE C0805
J 0
(3425 825);
DISPLAY 0.617021 (3425 825);
PAINT SKYBLUE (3425 825);
FORCEPROP 1 LAST LOCATION PC576_P1_1
J 0
(3425 1075);
DISPLAY 0.617021 (3425 1075);
PAINT AQUA (3425 1075);
FORCEPROP 1 LASTPIN (3375 1050) $PN 1
J 0
(3385 1030);
DISPLAY 0.617021 (3385 1030);
PAINT MONO (3385 1030);
FORCEPROP 1 LASTPIN (3375 850) $PN 2
J 0
(3385 830);
DISPLAY 0.617021 (3385 830);
PAINT MONO (3385 830);
FORCEPROP 2 LAST CDS_LIB pure_quanta
J 0
(3375 950);
DISPLAY INVISIBLE (3375 950);
FORCEPROP 1 LAST PATH I88
J 0
(3425 1100);
DISPLAY 0.978723 (3425 1100);
PAINT WHITE (3425 1100);
DISPLAY INVISIBLE (3425 1100);
FORCEPROP 1 LAST LOCATION PC576_P1_1
J 0
(3425 1125);
DISPLAY 1.021277 (3425 1125);
PAINT AQUA (3425 1125);
DISPLAY INVISIBLE (3425 1125);
FORCEPROP 0 LAST $SEC 1
J 0
(3425 1125);
DISPLAY 0.680851 (3425 1125);
PAINT MONO (3425 1125);
DISPLAY INVISIBLE (3425 1125);
FORCEPROP 0 LAST CDS_SEC 1
J 0
(3425 1125);
DISPLAY 1.021277 (3425 1125);
DISPLAY INVISIBLE (3425 1125);
FORCEADD VCC15..1
(4050 250);
FORCEPROP 3 LASTPIN (4050 200) SIG_NAME PVCCIN_CPU1\g
J 0
(4060 210);
DISPLAY 0.659574 (4060 210);
PAINT MONO (4060 210);
DISPLAY INVISIBLE (4060 210);
FORCEPROP 1 LAST HDL_POWER PVCCIN_CPU1
J 1
(4050 300);
DISPLAY 0.617021 (4050 300);
PAINT GREEN (4050 300);
FORCEPROP 2 LAST CDS_LIB logical_power
J 0
(4050 250);
DISPLAY INVISIBLE (4050 250);
FORCEPROP 1 LAST PATH I89
J 0
(4100 275);
DISPLAY 0.872340 (4100 275);
PAINT AQUA (4100 275);
DISPLAY INVISIBLE (4100 275);
FORCEADD OFFPAGE..1
(-3575 -1800);
FORCEPROP 2 LAST $XR6 290 
J 0
(-4577 -1800);
DISPLAY 0.638298 (-4577 -1800);
PAINT MONO (-4577 -1800);
FORCEPROP 2 LAST $XR5 289 
J 0
(-4457 -1800);
DISPLAY 0.638298 (-4457 -1800);
PAINT MONO (-4457 -1800);
FORCEPROP 2 LAST $XR4 288 
J 0
(-4337 -1800);
DISPLAY 0.638298 (-4337 -1800);
PAINT MONO (-4337 -1800);
FORCEPROP 2 LAST $XR3 287 
J 0
(-4217 -1800);
DISPLAY 0.638298 (-4217 -1800);
PAINT MONO (-4217 -1800);
FORCEPROP 2 LAST $XR2 286 
J 0
(-4097 -1800);
DISPLAY 0.638298 (-4097 -1800);
PAINT MONO (-4097 -1800);
FORCEPROP 2 LAST $XR1 285 
J 0
(-3977 -1800);
DISPLAY 0.638298 (-3977 -1800);
PAINT MONO (-3977 -1800);
FORCEPROP 2 LAST $XR0 284 
J 0
(-3857 -1800);
DISPLAY 0.638298 (-3857 -1800);
PAINT MONO (-3857 -1800);
FORCEPROP 1 LAST COMMENT_BODY TRUE
J 0
(-3450 -1900);
DISPLAY 0.872340 (-3450 -1900);
PAINT GREEN (-3450 -1900);
DISPLAY INVISIBLE (-3450 -1900);
FORCEPROP 1 LAST OFFPAGE TRUE
J 0
(-3250 -1925);
DISPLAY 0.872340 (-3250 -1925);
PAINT GREEN (-3250 -1925);
DISPLAY INVISIBLE (-3250 -1925);
FORCEPROP 2 LAST CDS_LIB standard
J 0
(-3575 -1800);
DISPLAY INVISIBLE (-3575 -1800);
FORCEPROP 2 LAST PATH I9
J 0
(-3850 -1750);
DISPLAY 1.021277 (-3850 -1750);
DISPLAY INVISIBLE (-3850 -1750);
FORCEADD UNIVERSAL_GND..1
(4100 575);
FORCEPROP 3 LASTPIN (4100 625) SIG_NAME GND\g
J 0
(4110 635);
DISPLAY 0.659574 (4110 635);
PAINT MONO (4110 635);
DISPLAY INVISIBLE (4110 635);
FORCEPROP 1 LAST HDL_POWER GND
J 1
(4125 500);
DISPLAY 0.872340 (4125 500);
PAINT GREEN (4125 500);
DISPLAY INVISIBLE (4125 500);
FORCEPROP 2 LAST CDS_LIB logical_power
J 0
(4100 575);
PAINT MONO (4100 575);
DISPLAY INVISIBLE (4100 575);
FORCEPROP 1 LAST PATH I90
J 0
(4175 575);
DISPLAY 0.872340 (4175 575);
PAINT AQUA (4175 575);
DISPLAY INVISIBLE (4175 575);
FORCEADD Q_CAP..1
(3800 950);
FORCEPROP 1 LAST PART_NUMBER CH622KMEA03
J 0
(3850 775);
DISPLAY 0.617021 (3850 775);
PAINT BLUE (3850 775);
DISPLAY INVISIBLE (3850 775);
FORCEPROP 1 LAST TOLERANCE 20%
J 0
(3850 925);
DISPLAY 0.617021 (3850 925);
PAINT SKYBLUE (3850 925);
FORCEPROP 1 LAST MATERIAL X6S
J 0
(3850 875);
DISPLAY 0.617021 (3850 875);
PAINT SKYBLUE (3850 875);
FORCEPROP 1 LAST VALUE 22UF
J 0
(3850 1025);
DISPLAY 0.617021 (3850 1025);
PAINT SKYBLUE (3850 1025);
FORCEPROP 1 LAST VOLTAGE 4V
J 0
(3850 975);
DISPLAY 0.617021 (3850 975);
PAINT SKYBLUE (3850 975);
FORCEPROP 1 LAST PACK_TYPE C0805
J 0
(3850 825);
DISPLAY 0.617021 (3850 825);
PAINT SKYBLUE (3850 825);
FORCEPROP 1 LAST LOCATION PC578_P1_1
J 0
(3850 1075);
DISPLAY 0.617021 (3850 1075);
PAINT AQUA (3850 1075);
FORCEPROP 1 LASTPIN (3800 1050) $PN 1
J 0
(3810 1030);
DISPLAY 0.617021 (3810 1030);
PAINT MONO (3810 1030);
FORCEPROP 1 LASTPIN (3800 850) $PN 2
J 0
(3810 830);
DISPLAY 0.617021 (3810 830);
PAINT MONO (3810 830);
FORCEPROP 2 LAST CDS_LIB pure_quanta
J 0
(3800 950);
DISPLAY INVISIBLE (3800 950);
FORCEPROP 1 LAST PATH I91
J 0
(3850 1100);
DISPLAY 0.978723 (3850 1100);
PAINT WHITE (3850 1100);
DISPLAY INVISIBLE (3850 1100);
FORCEPROP 1 LAST LOCATION PC578_P1_1
J 0
(3850 1125);
DISPLAY 1.021277 (3850 1125);
PAINT AQUA (3850 1125);
DISPLAY INVISIBLE (3850 1125);
FORCEPROP 0 LAST $SEC 1
J 0
(3850 1125);
DISPLAY 0.680851 (3850 1125);
PAINT MONO (3850 1125);
DISPLAY INVISIBLE (3850 1125);
FORCEPROP 0 LAST CDS_SEC 1
J 0
(3850 1125);
DISPLAY 1.021277 (3850 1125);
DISPLAY INVISIBLE (3850 1125);
FORCEADD Q_CAPP..1
(3300 2250);
FORCEPROP 1 LAST PART_NUMBER CC72703MD38
J 0
(3350 2075);
DISPLAY 0.617021 (3350 2075);
PAINT BLUE (3350 2075);
DISPLAY INVISIBLE (3350 2075);
FORCEPROP 1 LAST VOLTAGE 16V
J 0
(3350 2225);
DISPLAY 0.617021 (3350 2225);
PAINT SKYBLUE (3350 2225);
FORCEPROP 1 LAST TOLERANCE 20%
J 0
(3350 2275);
DISPLAY 0.617021 (3350 2275);
PAINT SKYBLUE (3350 2275);
FORCEPROP 1 LAST PACK_TYPE THLF
J 0
(3350 2125);
DISPLAY 0.617021 (3350 2125);
PAINT SKYBLUE (3350 2125);
FORCEPROP 1 LAST MATERIAL OSCON
J 0
(3350 2175);
DISPLAY 0.617021 (3350 2175);
PAINT SKYBLUE (3350 2175);
FORCEPROP 1 LAST VALUE 270UF
J 0
(3350 2325);
DISPLAY 0.617021 (3350 2325);
PAINT SKYBLUE (3350 2325);
FORCEPROP 1 LAST LOCATION PC585
J 0
(3350 2375);
DISPLAY 0.617021 (3350 2375);
PAINT AQUA (3350 2375);
FORCEPROP 1 LASTPIN (3300 2350) $PN 1
J 0
(3310 2335);
DISPLAY 0.617021 (3310 2335);
PAINT MONO (3310 2335);
FORCEPROP 1 LASTPIN (3300 2150) $PN 2
J 0
(3310 2135);
DISPLAY 0.617021 (3310 2135);
PAINT MONO (3310 2135);
FORCEPROP 2 LAST CDS_LIB pure_quanta
J 0
(3300 2250);
DISPLAY INVISIBLE (3300 2250);
FORCEPROP 1 LAST PATH I92
J 0
(3350 2400);
DISPLAY 0.978723 (3350 2400);
DISPLAY INVISIBLE (3350 2400);
FORCEPROP 1 LAST LOCATION PC585
J 0
(3350 2425);
DISPLAY 1.021277 (3350 2425);
PAINT AQUA (3350 2425);
DISPLAY INVISIBLE (3350 2425);
FORCEPROP 0 LAST $SEC 1
J 0
(3350 2425);
DISPLAY 0.680851 (3350 2425);
PAINT MONO (3350 2425);
DISPLAY INVISIBLE (3350 2425);
FORCEPROP 0 LAST CDS_SEC 1
J 0
(3350 2425);
DISPLAY 1.021277 (3350 2425);
DISPLAY INVISIBLE (3350 2425);
FORCEADD VCC15..1
(4100 1350);
FORCEPROP 3 LASTPIN (4100 1300) SIG_NAME PVCCIN_CPU1\g
J 0
(4110 1310);
DISPLAY 0.659574 (4110 1310);
PAINT MONO (4110 1310);
DISPLAY INVISIBLE (4110 1310);
FORCEPROP 1 LAST HDL_POWER PVCCIN_CPU1
J 1
(4100 1400);
DISPLAY 0.617021 (4100 1400);
PAINT GREEN (4100 1400);
FORCEPROP 2 LAST CDS_LIB logical_power
J 0
(4100 1350);
DISPLAY INVISIBLE (4100 1350);
FORCEPROP 1 LAST PATH I93
J 0
(4150 1375);
DISPLAY 0.872340 (4150 1375);
PAINT AQUA (4150 1375);
DISPLAY INVISIBLE (4150 1375);
FORCEADD Q_CAPP..1
(3700 2250);
FORCEPROP 1 LAST PART_NUMBER CC72703MD38
J 0
(3750 2075);
DISPLAY 0.617021 (3750 2075);
PAINT BLUE (3750 2075);
DISPLAY INVISIBLE (3750 2075);
FORCEPROP 1 LAST MATERIAL OSCON
J 0
(3750 2175);
DISPLAY 0.617021 (3750 2175);
PAINT SKYBLUE (3750 2175);
FORCEPROP 1 LAST VOLTAGE 16V
J 0
(3750 2225);
DISPLAY 0.617021 (3750 2225);
PAINT SKYBLUE (3750 2225);
FORCEPROP 1 LAST VALUE 270UF
J 0
(3750 2325);
DISPLAY 0.617021 (3750 2325);
PAINT SKYBLUE (3750 2325);
FORCEPROP 1 LAST TOLERANCE 20%
J 0
(3750 2275);
DISPLAY 0.617021 (3750 2275);
PAINT SKYBLUE (3750 2275);
FORCEPROP 1 LAST PACK_TYPE THLF
J 0
(3750 2125);
DISPLAY 0.617021 (3750 2125);
PAINT SKYBLUE (3750 2125);
FORCEPROP 1 LAST LOCATION PC588
J 0
(3750 2375);
DISPLAY 0.617021 (3750 2375);
PAINT AQUA (3750 2375);
FORCEPROP 1 LASTPIN (3700 2350) $PN 1
J 0
(3710 2335);
DISPLAY 0.617021 (3710 2335);
PAINT MONO (3710 2335);
FORCEPROP 1 LASTPIN (3700 2150) $PN 2
J 0
(3710 2135);
DISPLAY 0.617021 (3710 2135);
PAINT MONO (3710 2135);
FORCEPROP 2 LAST CDS_LIB pure_quanta
J 0
(3700 2250);
DISPLAY INVISIBLE (3700 2250);
FORCEPROP 1 LAST PATH I94
J 0
(3750 2400);
DISPLAY 0.978723 (3750 2400);
DISPLAY INVISIBLE (3750 2400);
FORCEPROP 1 LAST LOCATION PC588
J 0
(3750 2425);
DISPLAY 1.021277 (3750 2425);
PAINT AQUA (3750 2425);
DISPLAY INVISIBLE (3750 2425);
FORCEPROP 0 LAST $SEC 1
J 0
(3750 2425);
DISPLAY 0.680851 (3750 2425);
PAINT MONO (3750 2425);
DISPLAY INVISIBLE (3750 2425);
FORCEPROP 0 LAST CDS_SEC 1
J 0
(3750 2425);
DISPLAY 1.021277 (3750 2425);
DISPLAY INVISIBLE (3750 2425);
FORCEADD UNIVERSAL_GND..1
(4100 1925);
FORCEPROP 3 LASTPIN (4100 1975) SIG_NAME GND\g
J 0
(4110 1985);
DISPLAY 0.659574 (4110 1985);
PAINT MONO (4110 1985);
DISPLAY INVISIBLE (4110 1985);
FORCEPROP 1 LAST HDL_POWER GND
J 1
(4125 1850);
DISPLAY 0.872340 (4125 1850);
PAINT GREEN (4125 1850);
DISPLAY INVISIBLE (4125 1850);
FORCEPROP 2 LAST CDS_LIB logical_power
J 0
(4100 1925);
PAINT MONO (4100 1925);
DISPLAY INVISIBLE (4100 1925);
FORCEPROP 1 LAST PATH I95
J 0
(4175 1925);
DISPLAY 0.872340 (4175 1925);
PAINT AQUA (4175 1925);
DISPLAY INVISIBLE (4175 1925);
FORCEADD Q_CAPP..1
(4100 2250);
FORCEPROP 1 LAST PART_NUMBER CC72703MD38
J 0
(4150 2075);
DISPLAY 0.638298 (4150 2075);
PAINT BLUE (4150 2075);
DISPLAY INVISIBLE (4150 2075);
FORCEPROP 1 LAST VALUE 270UF
J 0
(4150 2325);
DISPLAY 0.638298 (4150 2325);
PAINT SKYBLUE (4150 2325);
FORCEPROP 1 LAST TOLERANCE 20%
J 0
(4150 2275);
DISPLAY 0.638298 (4150 2275);
PAINT SKYBLUE (4150 2275);
FORCEPROP 1 LAST VOLTAGE 16V
J 0
(4150 2225);
DISPLAY 0.638298 (4150 2225);
PAINT SKYBLUE (4150 2225);
FORCEPROP 1 LAST MATERIAL OSCON
J 0
(4150 2175);
DISPLAY 0.638298 (4150 2175);
PAINT SKYBLUE (4150 2175);
FORCEPROP 1 LAST PACK_TYPE THLF
J 0
(4150 2125);
DISPLAY 0.638298 (4150 2125);
PAINT SKYBLUE (4150 2125);
FORCEPROP 1 LAST LOCATION PC2346
J 0
(4150 2375);
DISPLAY 0.638298 (4150 2375);
PAINT AQUA (4150 2375);
FORCEPROP 1 LASTPIN (4100 2350) $PN 1
J 0
(4110 2335);
DISPLAY 0.787234 (4110 2335);
PAINT MONO (4110 2335);
FORCEPROP 1 LASTPIN (4100 2150) $PN 2
J 0
(4110 2135);
DISPLAY 0.787234 (4110 2135);
PAINT MONO (4110 2135);
FORCEPROP 2 LAST CDS_LIB pure_quanta
J 0
(4100 2250);
DISPLAY INVISIBLE (4100 2250);
FORCEPROP 1 LAST PATH I96
J 0
(4150 2400);
DISPLAY 0.978723 (4150 2400);
DISPLAY INVISIBLE (4150 2400);
FORCEPROP 0 LAST $SEC 1
J 0
(4150 2425);
DISPLAY 0.680851 (4150 2425);
PAINT MONO (4150 2425);
DISPLAY INVISIBLE (4150 2425);
FORCEPROP 0 LAST CDS_SEC 1
J 0
(4150 2425);
DISPLAY 1.021277 (4150 2425);
DISPLAY INVISIBLE (4150 2425);
FORCEADD VCC15..1
(4100 2575);
FORCEPROP 3 LASTPIN (4100 2525) SIG_NAME SW_P12V_PVCCIN_CPU1_FLT\g
J 0
(4110 2535);
DISPLAY 0.659574 (4110 2535);
PAINT MONO (4110 2535);
DISPLAY INVISIBLE (4110 2535);
FORCEPROP 1 LAST HDL_POWER SW_P12V_PVCCIN_CPU1_FLT
J 1
(4150 2625);
DISPLAY 0.617021 (4150 2625);
PAINT GREEN (4150 2625);
FORCEPROP 2 LAST CDS_LIB logical_power
J 0
(4100 2575);
DISPLAY INVISIBLE (4100 2575);
FORCEPROP 1 LAST PATH I97
J 0
(4150 2600);
DISPLAY 0.872340 (4150 2600);
PAINT AQUA (4150 2600);
DISPLAY INVISIBLE (4150 2600);
FORCEADD QUANTA_TITLE_BLOCK_C..1
(4675 -3275);
FORCEPROP 0 LAST CDS_CON_LAST_MODIFIED Fri Aug 25 14:04:55 2023
J 0
(2790 -3260);
DISPLAY INVISIBLE (2790 -3260);
FORCEPROP 1 LAST CUSTOM_TXT_CDS <CON_LAST_MODIFIED>
J 0
(2790 -3260);
DISPLAY 0.978723 (2790 -3260);
FORCEPROP 2 LAST CUSTOM_TXT_CDS <XR_PAGE_TITLE>
J 0
(-3215 1975);
DISPLAY 0.638298 (-3215 1975);
PAINT PINK (-3215 1975);
DISPLAY INVISIBLE (-3215 1975);
FORCEPROP 1 LAST CUSTOM_TXT_CDS <NAME_2>
J 0
(1500 -3225);
FORCEPROP 1 LAST CUSTOM_TXT_CDS <NAME_1>
J 0
(1500 -3100);
FORCEPROP 1 LAST CUSTOM_TXT_CDS <Q_NUMBER>
J 0
(3272 -3172);
DISPLAY 1.212766 (3272 -3172);
FORCEPROP 1 LAST CUSTOM_TXT_CDS <Q_PROJ>
J 0
(2293 -3173);
DISPLAY 1.212766 (2293 -3173);
FORCEPROP 1 LAST CUSTOM_TXT_CDS <Q_REV>
J 0
(4491 -3172);
DISPLAY 1.212766 (4491 -3172);
FORCEPROP 1 LAST CUSTOM_TXT_CDS <CON_PAGE_NUM> OF <CON_TOTAL_PAGES>
J 0
(4229 -3257);
DISPLAY 0.978723 (4229 -3257);
FORCEPROP 1 LAST Q_TITLE VCCIN CPU1 VR PHASE 1&2 (2/7)
J 0
(-4625 -3225);
DISPLAY 2.446809 (-4625 -3225);
PAINT GREEN (-4625 -3225);
FORCEPROP 1 LAST Q_DEPT 
J 1
(912 -3226);
DISPLAY 1.957447 (912 -3226);
PAINT GREEN (912 -3226);
FORCEPROP 2 LAST CDS_XR_PAGE_TITLE CR-285 : @S9S_MB_2U_LIB.S9S_MB_2U(SCH_1):PAGE285
J 0
(-3215 1975);
DISPLAY 0.638298 (-3215 1975);
PAINT PINK (-3215 1975);
DISPLAY INVISIBLE (-3215 1975);
FORCEPROP 2 LAST CDS_LIB pure_quanta
J 0
(4675 -3275);
DISPLAY INVISIBLE (4675 -3275);
FORCEPROP 1 LAST CDS_LMAN_SYM_OUTLINE -9475,6775,100,-125
J 0
(4675 -3275);
DISPLAY 0.468085 (4675 -3275);
PAINT GREEN (4675 -3275);
DISPLAY INVISIBLE (4675 -3275);
FORCEPROP 2 LAST PAGE_BORDER TRUE
J 0
(-3215 1975);
DISPLAY 0.638298 (-3215 1975);
PAINT PINK (-3215 1975);
DISPLAY INVISIBLE (-3215 1975);
FORCEPROP 1 LAST COMMENT_BODY TRUE
J 0
(4687 -3288);
DISPLAY 0.978723 (4687 -3288);
PAINT GREEN (4687 -3288);
DISPLAY INVISIBLE (4687 -3288);
FORCEADD DNS..1
(-4050 -2225);
PAINT RED (-4050 -2225);
FORCEPROP 1 LAST COMMENT_BODY TRUE
R 1
J 0
(-3975 -2450);
DISPLAY 0.872340 (-3975 -2450);
PAINT GREEN (-3975 -2450);
DISPLAY INVISIBLE (-3975 -2450);
FORCEPROP 2 LAST CDS_LIB mstr_misc
J 0
(-4050 -2225);
PAINT MONO (-4050 -2225);
DISPLAY INVISIBLE (-4050 -2225);
FORCEADD DNS..1
(-4025 600);
PAINT RED (-4025 600);
FORCEPROP 1 LAST COMMENT_BODY TRUE
R 1
J 0
(-3950 375);
DISPLAY 0.872340 (-3950 375);
PAINT GREEN (-3950 375);
DISPLAY INVISIBLE (-3950 375);
FORCEPROP 2 LAST CDS_LIB mstr_misc
J 0
(-4025 600);
PAINT MONO (-4025 600);
DISPLAY INVISIBLE (-4025 600);
FORCEADD DNS..1
(-3425 2775);
PAINT RED (-3425 2775);
FORCEPROP 1 LAST COMMENT_BODY TRUE
R 1
J 0
(-3350 2550);
DISPLAY 0.872340 (-3350 2550);
PAINT GREEN (-3350 2550);
DISPLAY INVISIBLE (-3350 2550);
FORCEPROP 2 LAST CDS_LIB mstr_misc
J 0
(-3425 2775);
DISPLAY INVISIBLE (-3425 2775);
FORCEADD DNS..1
(2625 -950);
PAINT RED (2625 -950);
FORCEPROP 2 LAST CDS_LIB mstr_misc
J 0
(2625 -950);
DISPLAY INVISIBLE (2625 -950);
FORCEPROP 1 LAST COMMENT_BODY TRUE
R 1
J 0
(2700 -1175);
DISPLAY 0.872340 (2700 -1175);
PAINT GREEN (2700 -1175);
DISPLAY INVISIBLE (2700 -1175);
FORCEADD DNS..1
(3125 -950);
PAINT RED (3125 -950);
FORCEPROP 1 LAST COMMENT_BODY TRUE
R 1
J 0
(3200 -1175);
DISPLAY 0.872340 (3200 -1175);
PAINT GREEN (3200 -1175);
DISPLAY INVISIBLE (3200 -1175);
FORCEPROP 2 LAST CDS_LIB mstr_misc
J 0
(3125 -950);
DISPLAY INVISIBLE (3125 -950);
FORCEADD DNS..1
(3575 -950);
PAINT RED (3575 -950);
FORCEPROP 1 LAST COMMENT_BODY TRUE
R 1
J 0
(3650 -1175);
DISPLAY 0.872340 (3650 -1175);
PAINT GREEN (3650 -1175);
DISPLAY INVISIBLE (3650 -1175);
FORCEPROP 2 LAST CDS_LIB mstr_misc
J 0
(3575 -950);
DISPLAY INVISIBLE (3575 -950);
FORCEADD DNS..1
(4050 -925);
PAINT RED (4050 -925);
FORCEPROP 2 LAST CDS_LIB mstr_misc
J 0
(4050 -925);
DISPLAY INVISIBLE (4050 -925);
FORCEPROP 1 LAST COMMENT_BODY TRUE
R 1
J 0
(4125 -1150);
DISPLAY 0.872340 (4125 -1150);
PAINT GREEN (4125 -1150);
DISPLAY INVISIBLE (4125 -1150);
FORCEADD DNS..1
(1950 2325);
PAINT RED (1950 2325);
FORCEPROP 1 LAST COMMENT_BODY TRUE
R 1
J 0
(2025 2100);
DISPLAY 0.872340 (2025 2100);
PAINT GREEN (2025 2100);
DISPLAY INVISIBLE (2025 2100);
FORCEPROP 2 LAST CDS_LIB mstr_misc
J 0
(1950 2325);
DISPLAY INVISIBLE (1950 2325);
WIRE 16 -1 (-3650 -475)(-3650 -425);
WIRE 16 -1 (-3225 -475)(-3650 -475);
WIRE 16 -1 (-3650 -600)(-3650 -475);
WIRE 16 -1 (-4125 2975)(-4125 2900);
WIRE 16 -1 (-3475 2975)(-3475 2900);
WIRE 16 -1 (475 -475)(475 -550);
WIRE 16 -1 (4075 -1725)(4075 -1775);
WIRE 16 -1 (4050 -675)(4050 -725);
WIRE 16 -1 (500 2350)(500 2275);
WIRE 16 -1 (1400 2575)(1400 2450);
WIRE 16 -1 (4050 200)(4050 150);
WIRE 16 -1 (4100 1300)(4100 1150);
WIRE 16 -1 (4100 2525)(4100 2450);
WIRE 16 -1 (-4150 -1900)(-4150 -1925);
WIRE 16 -1 (-4150 -1900)(-3425 -1900);
WIRE 16 -1 (-4050 -2300)(-4050 -2375);
WIRE 16 -1 (-3650 -1300)(-3650 -1400);
WIRE 16 -1 (-3225 -800)(-3225 -875);
WIRE 16 -1 (-1475 -2300)(-1475 -2375);
WIRE 16 -1 (-1475 -2250)(-1475 -2300);
WIRE 16 -1 (-1725 -2300)(-1475 -2300);
WIRE 16 -1 (-4125 925)(-4125 900);
WIRE 16 -1 (-4125 925)(-3400 925);
WIRE 16 -1 (-4025 525)(-4025 450);
WIRE 16 -1 (-3625 1525)(-3625 1425);
WIRE 16 -1 (-3200 2025)(-3200 1950);
WIRE 16 -1 (-1450 525)(-1450 450);
WIRE 16 -1 (-1450 575)(-1450 525);
WIRE 16 -1 (-1700 525)(-1450 525);
WIRE 16 -1 (475 -1175)(475 -1050);
WIRE 16 -1 (4075 -2325)(4075 -2200);
WIRE 16 -1 (4050 -1225)(4050 -1150);
WIRE 16 -1 (4050 -350)(4050 -275);
WIRE 16 -1 (500 1650)(500 1775);
WIRE 16 -1 (1400 2050)(1400 2150);
WIRE 16 -1 (4100 625)(4100 725);
WIRE 16 -1 (4100 1975)(4100 2050);
WIRE 16 -1 (4050 -175)(4050 -275);
WIRE 16 -1 (2025 -275)(2025 -150);
WIRE 16 -1 (3550 -175)(3550 -275);
WIRE 16 -1 (4050 -275)(3550 -275);
WIRE 16 -1 (3025 -275)(3025 -175);
WIRE 16 -1 (3025 -275)(3550 -275);
WIRE 16 -1 (2500 -275)(2025 -275);
WIRE 16 -1 (2500 -175)(2500 -275);
WIRE 16 -1 (2500 -275)(3025 -275);
WIRE 16 -1 (4050 25)(4050 150);
WIRE 16 -1 (3550 25)(3550 150);
WIRE 16 -1 (4050 150)(3550 150);
WIRE 16 -1 (3025 150)(3025 25);
WIRE 16 -1 (3025 150)(3550 150);
WIRE 16 -1 (2500 25)(2500 150);
WIRE 16 -1 (2500 150)(3025 150);
WIRE 16 -1 (2025 150)(2500 150);
WIRE 16 -1 (2025 50)(2025 150);
WIRE 16 -1 (4050 -1050)(4050 -1150);
WIRE 16 -1 (3550 -1050)(3550 -1150);
WIRE 16 -1 (4050 -1150)(3550 -1150);
WIRE 16 -1 (3100 -1025)(3100 -1150);
WIRE 16 -1 (3100 -1150)(3550 -1150);
WIRE 16 -1 (3100 -1150)(2600 -1150);
WIRE 16 -1 (2600 -1050)(2600 -1150);
WIRE 16 -1 (4050 -850)(4050 -725);
WIRE 16 -1 (3550 -850)(3550 -725);
WIRE 16 -1 (4050 -725)(3550 -725);
WIRE 16 -1 (3100 -825)(3100 -725);
WIRE 16 -1 (3100 -725)(3550 -725);
WIRE 16 -1 (3100 -725)(2600 -725);
WIRE 16 -1 (2600 -850)(2600 -725);
WIRE 16 -1 (4100 2150)(4100 2050);
WIRE 16 -1 (3700 2150)(3700 2050);
WIRE 16 -1 (4100 2050)(3700 2050);
WIRE 16 -1 (3300 2150)(3300 2050);
WIRE 16 -1 (3300 2050)(3700 2050);
WIRE 16 -1 (2900 2150)(2900 2050);
WIRE 16 -1 (3300 2050)(2900 2050);
WIRE 16 -1 (2500 2050)(2900 2050);
WIRE 16 -1 (2500 2150)(2500 2050);
WIRE 16 -1 (4100 2450)(4100 2350);
WIRE 16 -1 (3700 2350)(3700 2450);
WIRE 16 -1 (4100 2450)(3700 2450);
WIRE 16 -1 (2325 2325)(2025 2325);
WIRE 16 -1 (2325 2450)(2025 2450);
WIRE 16 -1 (2325 2450)(2325 2325);
WIRE 16 -1 (3300 2350)(3300 2450);
WIRE 16 -1 (3300 2450)(3700 2450);
WIRE 16 -1 (2900 2350)(2900 2450);
WIRE 16 -1 (3300 2450)(2900 2450);
WIRE 16 -1 (2500 2450)(2325 2450);
WIRE 16 -1 (2500 2450)(2500 2350);
WIRE 16 -1 (2500 2450)(2900 2450);
WIRE 16 -1 (3800 1050)(3800 1150);
WIRE 16 -1 (4100 1150)(3800 1150);
WIRE 16 -1 (3375 1150)(3375 1050);
WIRE 16 -1 (3375 1150)(3800 1150);
WIRE 16 -1 (2950 1050)(2950 1150);
WIRE 16 -1 (2950 1150)(3375 1150);
WIRE 16 -1 (2550 1050)(2550 1150);
WIRE 16 -1 (2550 1150)(2950 1150);
WIRE 16 -1 (1175 1150)(2400 1150);
WIRE 16 -1 (2400 1150)(2550 1150);
WIRE 16 -1 (2400 600)(275 600);
WIRE 16 -1 (2400 600)(2400 1150);
WIRE 16 -1 (3800 850)(3800 725);
WIRE 16 -1 (4100 725)(3800 725);
WIRE 16 -1 (3375 725)(3375 850);
WIRE 16 -1 (3800 725)(3375 725);
WIRE 16 -1 (2950 850)(2950 725);
WIRE 16 -1 (2950 725)(3375 725);
WIRE 16 -1 (2550 725)(2950 725);
WIRE 16 -1 (2550 850)(2550 725);
WIRE 16 -1 (1600 2325)(1825 2325);
WIRE 16 -1 (1600 2450)(1600 2325);
WIRE 16 -1 (1825 2450)(1600 2450);
WIRE 16 -1 (1400 2450)(1600 2450);
WIRE 16 -1 (1400 2350)(1400 2450);
WIRE 16 -1 (275 2125)(275 2275);
WIRE 16 -1 (500 2275)(275 2275);
WIRE 16 -1 (-100 2125)(-100 2275);
WIRE 16 -1 (-100 2275)(275 2275);
WIRE 16 -1 (-500 2275)(-500 2125);
WIRE 16 -1 (-500 2275)(-100 2275);
WIRE 16 -1 (-900 2125)(-900 2275);
WIRE 16 -1 (-900 2275)(-500 2275);
WIRE 16 -1 (-1300 2125)(-1300 2275);
WIRE 16 -1 (-1300 2275)(-900 2275);
WIRE 16 -1 (-1525 2275)(-1300 2275);
WIRE 16 -1 (-1700 1775)(-1525 1775);
WIRE 16 -1 (-1525 2275)(-1525 1775);
WIRE 16 -1 (-1525 1725)(-1525 1775);
WIRE 16 -1 (-1700 1725)(-1525 1725);
WIRE 16 -1 (1175 900)(1700 900);
FORCEPROP 2 LAST SIG_NAME IND_P1_CPL6
J 0
(1290 910);
DISPLAY 0.617021 (1290 910);
WIRE 16 -1 (500 1775)(275 1775);
WIRE 16 -1 (275 1925)(275 1775);
WIRE 16 -1 (-100 1925)(-100 1775);
WIRE 16 -1 (-100 1775)(275 1775);
WIRE 16 -1 (-500 1925)(-500 1775);
WIRE 16 -1 (-500 1775)(-100 1775);
WIRE 16 -1 (-900 1925)(-900 1775);
WIRE 16 -1 (-500 1775)(-900 1775);
WIRE 16 -1 (-1300 1775)(-900 1775);
WIRE 16 -1 (-1300 1925)(-1300 1775);
WIRE 17 273 (4500 450)(4500 -1425);
WIRE 17 273 (1950 450)(4500 450);
WIRE 17 273 (1950 -1425)(4500 -1425);
WIRE 17 273 (1950 -1425)(1950 450);
WIRE 16 -1 (3700 -1775)(3700 -1875);
WIRE 16 -1 (3700 -1775)(4075 -1775);
WIRE 16 -1 (3200 -1775)(3200 -1875);
WIRE 16 -1 (3200 -1775)(3700 -1775);
WIRE 16 -1 (2775 -1775)(2775 -1875);
WIRE 16 -1 (2775 -1775)(3200 -1775);
WIRE 16 -1 (700 -1700)(1825 -1700);
WIRE 16 -1 (1825 -1700)(1825 -1775);
WIRE 16 -1 (2775 -1775)(1825 -1775);
WIRE 16 -1 (1825 -2250)(1825 -1775);
WIRE 16 -1 (475 -2250)(1825 -2250);
WIRE 16 -1 (2775 -2200)(2775 -2075);
WIRE 16 -1 (3200 -2200)(2775 -2200);
WIRE 16 -1 (3200 -2200)(3200 -2075);
WIRE 16 -1 (3700 -2200)(3200 -2200);
WIRE 16 -1 (3700 -2075)(3700 -2200);
WIRE 16 -1 (4075 -2200)(3700 -2200);
WIRE 16 -1 (250 -700)(250 -550);
WIRE 16 -1 (475 -550)(250 -550);
WIRE 16 -1 (-125 -700)(-125 -550);
WIRE 16 -1 (-125 -550)(250 -550);
WIRE 16 -1 (-525 -550)(-525 -700);
WIRE 16 -1 (-525 -550)(-125 -550);
WIRE 16 -1 (-925 -700)(-925 -550);
WIRE 16 -1 (-925 -550)(-525 -550);
WIRE 16 -1 (-1325 -700)(-1325 -550);
WIRE 16 -1 (-1325 -550)(-925 -550);
WIRE 16 -1 (-1550 -550)(-1325 -550);
WIRE 16 -1 (-1725 -1050)(-1550 -1050);
WIRE 16 -1 (-1550 -550)(-1550 -1050);
WIRE 16 -1 (-1550 -1100)(-1550 -1050);
WIRE 16 -1 (-1725 -1100)(-1550 -1100);
WIRE 16 -1 (475 -1050)(250 -1050);
WIRE 16 -1 (250 -900)(250 -1050);
WIRE 16 -1 (-125 -900)(-125 -1050);
WIRE 16 -1 (-125 -1050)(250 -1050);
WIRE 16 -1 (-525 -1050)(-125 -1050);
WIRE 16 -1 (-525 -900)(-525 -1050);
WIRE 16 -1 (-525 -1050)(-925 -1050);
WIRE 16 -1 (-925 -900)(-925 -1050);
WIRE 16 -1 (-1325 -1050)(-925 -1050);
WIRE 16 -1 (-1325 -900)(-1325 -1050);
WIRE 16 -1 (700 -1950)(1450 -1950);
FORCEPROP 2 LAST SIG_NAME IND_P1_CPL1
J 0
(790 -1940);
DISPLAY 0.617021 (790 -1940);
WIRE 16 -1 (-175 900)(375 900);
FORCEPROP 2 LAST SIG_NAME IND_P1_CPL1
J 0
(-85 910);
DISPLAY 0.617021 (-85 910);
WIRE 16 -1 (-125 1575)(-125 1500);
WIRE 16 -1 (-750 1575)(-125 1575);
FORCEPROP 2 LAST SIG_NAME SW_PVCCIN_CPU1_BOOT1_R
J 0
(-560 1585);
DISPLAY 0.617021 (-560 1585);
WIRE 16 -1 (-975 600)(75 600);
WIRE 16 -1 (-975 875)(-975 600);
WIRE 16 -1 (-1700 875)(-975 875);
FORCEPROP 2 LAST SIG_NAME PVCCIN_CPU1_VOS1
J 0
(-1510 885);
DISPLAY 0.617021 (-1510 885);
WIRE 16 -1 (-125 1225)(-125 1300);
WIRE 16 -1 (-1700 1225)(-125 1225);
FORCEPROP 2 LAST SIG_NAME SW_PVCCIN_CPU1_BOOTR1
J 0
(-1510 1235);
DISPLAY 0.617021 (-1510 1235);
WIRE 16 -1 (-1550 1575)(-950 1575);
WIRE 16 -1 (-1550 1475)(-1550 1575);
FORCEPROP 2 LAST SIG_NAME SW_PVCCIN_CPU1_BOOT1
J 0
(-1660 1585);
DISPLAY 0.617021 (-1660 1585);
WIRE 16 -1 (-1700 1475)(-1550 1475);
WIRE 16 -1 (-1700 675)(-1450 675);
WIRE 16 -1 (-1700 625)(-1450 625);
WIRE 16 -1 (-1450 675)(-1450 625);
WIRE 16 -1 (-1450 625)(-1450 575);
WIRE 16 -1 (-1700 575)(-1450 575);
WIRE 16 -1 (-1700 1150)(-1700 1125);
WIRE 16 -1 (-1700 1150)(375 1150);
FORCEPROP 2 LAST SIG_NAME SW_PVCCIN_CPU1_SW1
J 0
(-1510 1160);
DISPLAY 0.617021 (-1510 1160);
WIRE 16 -1 (-2550 1775)(-2625 1775);
WIRE 16 -1 (-2625 1775)(-2625 2350);
WIRE 16 -1 (-3200 2350)(-3200 2225);
WIRE 16 -1 (-2625 2350)(-3200 2350);
WIRE 16 -1 (-3200 2350)(-3475 2350);
FORCEPROP 2 LAST SIG_NAME PVCCIN_CPU1_PVCC
J 0
(-3385 2360);
DISPLAY 0.617021 (-3385 2360);
WIRE 16 -1 (-3475 2700)(-3475 2350);
WIRE 16 -1 (-3625 2225)(-3625 2350);
WIRE 16 -1 (-3475 2350)(-3625 2350);
WIRE 16 -1 (-4125 2350)(-3625 2350);
WIRE 16 -1 (-4125 2700)(-4125 2350);
WIRE 16 -1 (-2550 1275)(-2650 1275);
WIRE 16 -1 (-2650 1275)(-2650 1475);
WIRE 16 -1 (-2650 1475)(-2550 1475);
WIRE 16 -1 (-3225 1475)(-2650 1475);
FORCEPROP 2 LAST SIG_NAME PVCCIN_CPU1_VDD1
J 0
(-3185 1485);
DISPLAY 0.617021 (-3185 1485);
WIRE 16 -1 (-3225 1475)(-3225 1875);
WIRE 16 -1 (-3625 1875)(-3625 1725);
WIRE 16 -1 (-3625 2025)(-3625 1875);
WIRE 16 -1 (-3625 1875)(-3225 1875);
WIRE 16 -1 (-2550 525)(-3500 525);
FORCEPROP 2 LAST SIG_NAME PVCCIN_CPU1_PWM1
J 0
(-3385 535);
DISPLAY 0.617021 (-3385 535);
WIRE 16 -1 (-2550 625)(-3500 625);
FORCEPROP 2 LAST SIG_NAME PVCCIN_CPU1_ATSEN
J 0
(-3385 635);
DISPLAY 0.617021 (-3385 635);
WIRE 16 -1 (-2550 1125)(-3500 1125);
FORCEPROP 2 LAST SIG_NAME PVCCIN_CPU1_IMON1
J 0
(-3385 1135);
DISPLAY 0.617021 (-3385 1135);
WIRE 16 -1 (-2650 925)(-3200 925);
WIRE 16 -1 (-3500 1025)(-2650 1025);
FORCEPROP 2 LAST SIG_NAME PVCCIN_CPU1_VREF
J 0
(-3385 1035);
DISPLAY 0.617021 (-3385 1035);
WIRE 16 -1 (-2650 1025)(-2650 925);
FORCEPROP 0 LAST CDS_PHYS_NET_NAME PVCCIN_CPU1_VREF
J 0
(-2650 950);
PAINT MONO (-2650 950);
DISPLAY INVISIBLE (-2650 950);
WIRE 16 -1 (-2650 1025)(-2550 1025);
WIRE 16 -1 (-4025 825)(-4025 725);
WIRE 16 -1 (-4025 825)(-2550 825);
FORCEPROP 2 LAST SIG_NAME PVCCIN_CPU1_LSET1
J 0
(-3385 835);
DISPLAY 0.617021 (-3385 835);
WIRE 16 -1 (-150 -1250)(-150 -1325);
WIRE 16 -1 (-775 -1250)(-150 -1250);
FORCEPROP 2 LAST SIG_NAME SW_PVCCIN_CPU1_BOOT2_R
J 0
(-585 -1240);
DISPLAY 0.617021 (-585 -1240);
WIRE 16 -1 (-1725 -1700)(-100 -1700);
FORCEPROP 2 LAST SIG_NAME SW_PVCCIN_CPU1_SW2
J 0
(-1535 -1690);
DISPLAY 0.617021 (-1535 -1690);
WIRE 16 -1 (-150 -1600)(-150 -1525);
WIRE 16 -1 (-1725 -1600)(-150 -1600);
FORCEPROP 0 LAST CDS_PHYS_NET_NAME SW_PVCCIN_CPU1_BOOTR2
J 0
(-1535 -1560);
PAINT MONO (-1535 -1560);
DISPLAY INVISIBLE (-1535 -1560);
FORCEPROP 2 LAST SIG_NAME SW_PVCCIN_CPU1_BOOTR2
J 0
(-1535 -1590);
DISPLAY 0.617021 (-1535 -1590);
WIRE 16 -1 (-1575 -1250)(-975 -1250);
FORCEPROP 0 LAST CDS_PHYS_NET_NAME SW_PVCCIN_CPU1_BOOT2
J 0
(-1535 -1221);
PAINT MONO (-1535 -1221);
DISPLAY INVISIBLE (-1535 -1221);
WIRE 16 -1 (-1575 -1350)(-1575 -1250);
FORCEPROP 2 LAST SIG_NAME SW_PVCCIN_CPU1_BOOT2
J 0
(-1685 -1240);
DISPLAY 0.617021 (-1685 -1240);
WIRE 16 -1 (-1725 -1350)(-1575 -1350);
WIRE 16 -1 (-650 -1950)(-100 -1950);
FORCEPROP 2 LAST SIG_NAME IND_P1_CPL2
J 0
(-610 -1940);
DISPLAY 0.617021 (-610 -1940);
WIRE 16 -1 (-1225 -2250)(275 -2250);
FORCEPROP 2 LAST SIG_NAME PVCCIN_CPU1_VOS2
J 0
(-1035 -2240);
DISPLAY 0.617021 (-1035 -2240);
WIRE 16 -1 (-1225 -1950)(-1225 -2250);
WIRE 16 -1 (-1725 -1950)(-1225 -1950);
WIRE 16 -1 (-1725 -2150)(-1475 -2150);
WIRE 16 -1 (-1725 -2200)(-1475 -2200);
WIRE 16 -1 (-1475 -2150)(-1475 -2200);
WIRE 16 -1 (-1475 -2200)(-1475 -2250);
WIRE 16 -1 (-1725 -2250)(-1475 -2250);
WIRE 16 -1 (-3225 -475)(-3225 -600);
WIRE 16 -1 (-2650 -475)(-3225 -475);
WIRE 16 -1 (-2650 -1050)(-2650 -475);
WIRE 16 -1 (-2575 -1050)(-2650 -1050);
WIRE 16 -1 (-2575 -1550)(-2675 -1550);
WIRE 16 -1 (-2675 -1550)(-2675 -1350);
WIRE 16 -1 (-2575 -1350)(-2675 -1350);
WIRE 16 -1 (-2675 -1350)(-3250 -1350);
FORCEPROP 2 LAST SIG_NAME PVCCIN_CPU1_VDD2
J 0
(-3210 -1340);
DISPLAY 0.617021 (-3210 -1340);
WIRE 16 -1 (-3250 -1350)(-3250 -950);
WIRE 16 -1 (-3650 -950)(-3650 -1100);
WIRE 16 -1 (-3650 -800)(-3650 -950);
WIRE 16 -1 (-3650 -950)(-3250 -950);
WIRE 16 -1 (-2575 -1700)(-3525 -1700);
FORCEPROP 2 LAST SIG_NAME PVCCIN_CPU1_IMON2
J 0
(-3410 -1690);
DISPLAY 0.617021 (-3410 -1690);
WIRE 16 -1 (-2675 -1900)(-3225 -1900);
WIRE 16 -1 (-3525 -1800)(-2675 -1800);
FORCEPROP 2 LAST SIG_NAME PVCCIN_CPU1_VREF
J 0
(-3410 -1790);
DISPLAY 0.617021 (-3410 -1790);
WIRE 16 -1 (-2675 -1800)(-2575 -1800);
WIRE 16 -1 (-2675 -1800)(-2675 -1900);
FORCEPROP 0 LAST CDS_PHYS_NET_NAME PVCCIN_CPU1_VREF
J 0
(-2675 -1875);
PAINT MONO (-2675 -1875);
DISPLAY INVISIBLE (-2675 -1875);
WIRE 16 -1 (-2575 -2300)(-3525 -2300);
FORCEPROP 2 LAST SIG_NAME PVCCIN_CPU1_PWM2
J 0
(-3410 -2290);
DISPLAY 0.617021 (-3410 -2290);
WIRE 16 -1 (-2575 -2200)(-3525 -2200);
FORCEPROP 2 LAST SIG_NAME PVCCIN_CPU1_ATSEN
J 0
(-3410 -2190);
DISPLAY 0.617021 (-3410 -2190);
WIRE 16 -1 (-4050 -2000)(-4050 -2100);
WIRE 16 -1 (-4050 -2000)(-2575 -2000);
FORCEPROP 2 LAST SIG_NAME PVCCIN_CPU1_LSET2
J 0
(-3410 -1990);
DISPLAY 0.617021 (-3410 -1990);
DOT 1 (-3650 -950);
DOT 1 (-3650 -475);
DOT 1 (-3225 -475);
DOT 1 (-2675 -1800);
DOT 1 (-2675 -1350);
DOT 1 (-1475 -2300);
DOT 1 (-1475 -2250);
DOT 1 (-1475 -2200);
DOT 1 (-1550 -1050);
DOT 1 (-1325 -550);
DOT 1 (-925 -1050);
DOT 1 (-525 -1050);
DOT 1 (-125 -1050);
DOT 1 (-925 -550);
DOT 1 (-525 -550);
DOT 1 (-125 -550);
DOT 1 (-3625 1875);
DOT 1 (-2650 1025);
DOT 1 (-2650 1475);
DOT 1 (-3625 2350);
DOT 1 (-3475 2350);
DOT 1 (-3200 2350);
DOT 1 (-1450 525);
DOT 1 (-1450 575);
DOT 1 (-1450 625);
DOT 1 (-1525 1775);
DOT 1 (-900 1775);
DOT 1 (-500 1775);
DOT 1 (-100 1775);
DOT 1 (-1300 2275);
DOT 1 (-900 2275);
DOT 1 (-500 2275);
DOT 1 (-100 2275);
DOT 1 (250 -1050);
DOT 1 (250 -550);
DOT 1 (1825 -1775);
DOT 1 (3200 -2200);
DOT 1 (3700 -2200);
DOT 1 (2775 -1775);
DOT 1 (2500 -275);
DOT 1 (2500 150);
DOT 1 (3025 -275);
DOT 1 (3025 150);
DOT 1 (3100 -725);
DOT 1 (3100 -1150);
DOT 1 (3200 -1775);
DOT 1 (3550 -1150);
DOT 1 (3700 -1775);
DOT 1 (4050 -1150);
DOT 1 (3550 -725);
DOT 1 (3550 -275);
DOT 1 (3550 150);
DOT 1 (4050 -725);
DOT 1 (4050 -275);
DOT 1 (4050 150);
DOT 1 (275 1775);
DOT 1 (275 2275);
DOT 1 (1400 2450);
DOT 1 (1600 2450);
DOT 1 (2400 1150);
DOT 1 (2550 1150);
DOT 1 (2950 725);
DOT 1 (2950 1150);
DOT 1 (2900 2050);
DOT 1 (3375 725);
DOT 1 (3375 1150);
DOT 1 (3800 725);
DOT 1 (3800 1150);
DOT 1 (3300 2050);
DOT 1 (3700 2050);
DOT 1 (4100 2050);
DOT 1 (2325 2450);
DOT 1 (2500 2450);
DOT 1 (2900 2450);
DOT 1 (3300 2450);
DOT 1 (3700 2450);
DOT 1 (4100 2450);
FORCENOTE
PVCCIN_CPU1_PHASE2
(-2500 -525) 0;
DISPLAY LEFT (-2500 -525);
DISPLAY 1.021277 (-2500 -525);
PAINT WHITE (-2500 -525);
FORCENOTE
PVCCIN_CPU1_PHASE1
(-2500 2300) 0;
DISPLAY LEFT (-2500 2300);
DISPLAY 1.021277 (-2500 2300);
PAINT WHITE (-2500 2300);
FORCENOTE
PGL6303.151HLT 
(650 -1250) 0;
DISPLAY LEFT (650 -1250);
DISPLAY 1.021277 (650 -1250);
FORCENOTE
DCR=2-3,0.27M OHM
(650 -1550) 0;
DISPLAY LEFT (650 -1550);
DISPLAY 1.021277 (650 -1550);
FORCENOTE
11.0*7.5*12.5
(650 -1325) 0;
DISPLAY LEFT (650 -1325);
DISPLAY 1.021277 (650 -1325);
FORCENOTE
ISAT=70A@100C
(650 -1400) 0;
DISPLAY LEFT (650 -1400);
DISPLAY 1.021277 (650 -1400);
FORCENOTE
DCR=1-4,0.105M OHM
(650 -1475) 0;
DISPLAY LEFT (650 -1475);
DISPLAY 1.021277 (650 -1475);
FORCENOTE
APPLY TO ALL RAILS.
(2575 -2825) 0;
DISPLAY LEFT (2575 -2825);
DISPLAY 1.021277 (2575 -2825);
FORCENOTE
RENESAS RECOMMEND BLEEDER RESISTOR
(2575 -2675) 0;
DISPLAY LEFT (2575 -2675);
DISPLAY 1.021277 (2575 -2675);
FORCENOTE
(499OHM) TO ABSORB LEAKAGE FROM SPS.
(2575 -2750) 0;
DISPLAY LEFT (2575 -2750);
DISPLAY 1.021277 (2575 -2750);
FORCENOTE
PGL6303.151HLT 
(1175 1500) 0;
DISPLAY LEFT (1175 1500);
DISPLAY 1.021277 (1175 1500);
FORCENOTE
11.0*7.5*12.5
(1175 1425) 0;
DISPLAY LEFT (1175 1425);
DISPLAY 1.021277 (1175 1425);
FORCENOTE
DCR=1-4,0.105M OHM
(1175 1275) 0;
DISPLAY LEFT (1175 1275);
DISPLAY 1.021277 (1175 1275);
FORCENOTE
DCR=2-3,0.27M OHM
(1175 1200) 0;
DISPLAY LEFT (1175 1200);
DISPLAY 1.021277 (1175 1200);
FORCENOTE
ISAT=70A@100C
(1175 1350) 0;
DISPLAY LEFT (1175 1350);
DISPLAY 1.021277 (1175 1350);
FORCENOTE
ESR=9.5M OHM
(2500 2000) 0;
DISPLAY LEFT (2500 2000);
DISPLAY 0.638298 (2500 2000);
FORCENOTE
RESERVE BY ARCHER CITY
(2875 500) 0;
DISPLAY LEFT (2875 500);
DISPLAY 1.021277 (2875 500);
PAINT WHITE (2875 500);
FORCENOTE
ESR=9.5M OHM
(2925 2000) 0;
DISPLAY LEFT (2925 2000);
DISPLAY 0.638298 (2925 2000);
FORCENOTE
ESR=9.5M OHM
(3325 2000) 0;
DISPLAY LEFT (3325 2000);
DISPLAY 0.638298 (3325 2000);
FORCENOTE
ESR=9.5M OHM
(3725 2000) 0;
DISPLAY LEFT (3725 2000);
DISPLAY 0.638298 (3725 2000);
FORCENOTE
DCR = 0.04M OHM
(2500 2550) 0;
DISPLAY LEFT (2500 2550);
DISPLAY 0.808511 (2500 2550);
FORCENOTE
10.0*8.3*8.0
(2500 2700) 0;
DISPLAY LEFT (2500 2700);
DISPLAY 0.808511 (2500 2700);
FORCENOTE
PGL6189.500HLT
(2500 2775) 0;
DISPLAY LEFT (2500 2775);
DISPLAY 0.808511 (2500 2775);
FORCENOTE
ISAT = 120A @ 100C
(2500 2625) 0;
DISPLAY LEFT (2500 2625);
DISPLAY 0.808511 (2500 2625);
QUIT
